FILE_TYPE = MACRO_DRAWING;
SET COLOR_WIRE YELLOW;
SET COLOR_PROP ORANGE;
SET COLOR_DOT WHITE;
SET COLOR_ARC YELLOW;
SET COLOR_BODY GREEN;
SET COLOR_NOTE PURPLE;
SET PROP_DISPLAY VALUE;
SET PAGE_NUMBER P168;
FORCEADD OFFPAGE..4
R 2
(-8700 1825);
FORCEPROP 2 LAST $XR0 82 
J 0
(-8921 1825);
DISPLAY 0.638298 (-8921 1825);
PAINT MONO (-8921 1825);
FORCEPROP 2 LAST CDS_LIB standard
J 0
(-8700 1825);
DISPLAY INVISIBLE (-8700 1825);
FORCEPROP 1 LAST OFFPAGE TRUE
J 2
(-9025 1700);
DISPLAY 0.872340 (-9025 1700);
PAINT GREEN (-9025 1700);
DISPLAY INVISIBLE (-9025 1700);
FORCEPROP 1 LAST COMMENT_BODY TRUE
J 2
(-8675 1725);
DISPLAY 0.872340 (-8675 1725);
PAINT GREEN (-8675 1725);
DISPLAY INVISIBLE (-8675 1725);
FORCEPROP 2 LAST PATH I1
J 0
(-8900 1875);
DISPLAY 0.680851 (-8900 1875);
DISPLAY INVISIBLE (-8900 1875);
FORCEADD Q_RES..2
(-7900 6375);
FORCEPROP 1 LAST LOCATION PR284
J 0
(-7850 6500);
DISPLAY 0.489362 (-7850 6500);
PAINT SKYBLUE (-7850 6500);
FORCEPROP 0 LAST $SEC 1
J 0
(-7850 6525);
DISPLAY 0.680851 (-7850 6525);
PAINT MONO (-7850 6525);
DISPLAY INVISIBLE (-7850 6525);
FORCEPROP 0 LAST CDS_SEC 1
J 0
(-7850 6525);
DISPLAY 1.021277 (-7850 6525);
DISPLAY INVISIBLE (-7850 6525);
FORCEPROP 1 LASTPIN (-7900 6475) $PN 1
J 0
(-7895 6437);
DISPLAY 0.489362 (-7895 6437);
PAINT MONO (-7895 6437);
FORCEPROP 1 LASTPIN (-7900 6275) $PN 2
J 0
(-7895 6285);
DISPLAY 0.489362 (-7895 6285);
PAINT MONO (-7895 6285);
FORCEPROP 1 LAST MATERIAL EMPTY
J 0
(-7850 6300);
DISPLAY 0.489362 (-7850 6300);
PAINT RED (-7850 6300);
FORCEPROP 1 LAST VALUE 1K
J 0
(-7850 6450);
DISPLAY 0.489362 (-7850 6450);
PAINT SKYBLUE (-7850 6450);
FORCEPROP 1 LAST WATTAGE 1/16W
J 0
(-7850 6350);
DISPLAY 0.489362 (-7850 6350);
PAINT SKYBLUE (-7850 6350);
FORCEPROP 1 LAST PACK_TYPE 0402LF
J 0
(-7850 6250);
DISPLAY 0.489362 (-7850 6250);
PAINT SKYBLUE (-7850 6250);
FORCEPROP 1 LAST TOLERANCE 1%
J 0
(-7850 6400);
DISPLAY 0.489362 (-7850 6400);
PAINT SKYBLUE (-7850 6400);
FORCEPROP 2 LAST CDS_LIB pure_quanta
J 0
(-7900 6375);
DISPLAY INVISIBLE (-7900 6375);
FORCEPROP 1 LAST PATH I10
J 0
(-7850 6550);
DISPLAY 0.978723 (-7850 6550);
PAINT WHITE (-7850 6550);
DISPLAY INVISIBLE (-7850 6550);
FORCEPROP 1 LAST PART_NUMBER CS21002FB06
J 0
(-7850 6250);
DISPLAY 0.489362 (-7850 6250);
PAINT SKYBLUE (-7850 6250);
DISPLAY INVISIBLE (-7850 6250);
FORCEADD OFFPAGE..4
(-2375 2100);
FORCEPROP 2 LAST $XR0 198 
J 0
(-2189 2100);
DISPLAY 0.638298 (-2189 2100);
PAINT MONO (-2189 2100);
FORCEPROP 2 LAST CDS_LIB standard
J 0
(-2375 2100);
DISPLAY INVISIBLE (-2375 2100);
FORCEPROP 1 LAST OFFPAGE TRUE
J 0
(-2050 1975);
DISPLAY 0.872340 (-2050 1975);
PAINT GREEN (-2050 1975);
DISPLAY INVISIBLE (-2050 1975);
FORCEPROP 1 LAST COMMENT_BODY TRUE
J 0
(-2400 2000);
DISPLAY 0.872340 (-2400 2000);
PAINT GREEN (-2400 2000);
DISPLAY INVISIBLE (-2400 2000);
FORCEPROP 2 LAST PATH I100
J 0
(-2175 2150);
DISPLAY 0.680851 (-2175 2150);
DISPLAY INVISIBLE (-2175 2150);
FORCEADD OFFPAGE..2
(-2375 2200);
FORCEPROP 2 LAST $XR0 198 
J 0
(-2186 2200);
DISPLAY 0.638298 (-2186 2200);
PAINT MONO (-2186 2200);
FORCEPROP 2 LAST CDS_LIB standard
J 0
(-2375 2200);
DISPLAY INVISIBLE (-2375 2200);
FORCEPROP 1 LAST OFFPAGE TRUE
J 0
(-2050 2075);
DISPLAY 0.872340 (-2050 2075);
PAINT GREEN (-2050 2075);
DISPLAY INVISIBLE (-2050 2075);
FORCEPROP 1 LAST COMMENT_BODY TRUE
J 0
(-2420 2105);
DISPLAY 0.872340 (-2420 2105);
PAINT GREEN (-2420 2105);
DISPLAY INVISIBLE (-2420 2105);
FORCEPROP 2 LAST PATH I101
J 0
(-2175 2250);
DISPLAY 0.680851 (-2175 2250);
DISPLAY INVISIBLE (-2175 2250);
FORCEADD OFFPAGE..4
(-2050 1600);
FORCEPROP 2 LAST $XR1 199 
J 0
(-1744 1600);
DISPLAY 0.638298 (-1744 1600);
PAINT MONO (-1744 1600);
FORCEPROP 2 LAST $XR0 198 
J 0
(-1864 1600);
DISPLAY 0.638298 (-1864 1600);
PAINT MONO (-1864 1600);
FORCEPROP 2 LAST CDS_LIB standard
J 0
(-2050 1600);
DISPLAY INVISIBLE (-2050 1600);
FORCEPROP 1 LAST OFFPAGE TRUE
J 0
(-1725 1475);
DISPLAY 0.872340 (-1725 1475);
PAINT GREEN (-1725 1475);
DISPLAY INVISIBLE (-1725 1475);
FORCEPROP 1 LAST COMMENT_BODY TRUE
J 0
(-2075 1500);
DISPLAY 0.872340 (-2075 1500);
PAINT GREEN (-2075 1500);
DISPLAY INVISIBLE (-2075 1500);
FORCEPROP 2 LAST PATH I102
J 0
(-1725 1650);
DISPLAY 0.680851 (-1725 1650);
DISPLAY INVISIBLE (-1725 1650);
FORCEADD OFFPAGE..2
(-2375 2800);
FORCEPROP 2 LAST $XR0 199 
J 0
(-2186 2800);
DISPLAY 0.638298 (-2186 2800);
PAINT MONO (-2186 2800);
FORCEPROP 2 LAST CDS_LIB standard
J 0
(-2375 2800);
DISPLAY INVISIBLE (-2375 2800);
FORCEPROP 1 LAST OFFPAGE TRUE
J 0
(-2050 2675);
DISPLAY 0.872340 (-2050 2675);
PAINT GREEN (-2050 2675);
DISPLAY INVISIBLE (-2050 2675);
FORCEPROP 1 LAST COMMENT_BODY TRUE
J 0
(-2420 2705);
DISPLAY 0.872340 (-2420 2705);
PAINT GREEN (-2420 2705);
DISPLAY INVISIBLE (-2420 2705);
FORCEPROP 2 LAST PATH I103
J 0
(-2175 2850);
DISPLAY 0.680851 (-2175 2850);
DISPLAY INVISIBLE (-2175 2850);
FORCEADD OFFPAGE..4
(-2375 2700);
FORCEPROP 2 LAST $XR0 199 
J 0
(-2189 2700);
DISPLAY 0.638298 (-2189 2700);
PAINT MONO (-2189 2700);
FORCEPROP 2 LAST CDS_LIB standard
J 0
(-2375 2700);
DISPLAY INVISIBLE (-2375 2700);
FORCEPROP 1 LAST OFFPAGE TRUE
J 0
(-2050 2575);
DISPLAY 0.872340 (-2050 2575);
PAINT GREEN (-2050 2575);
DISPLAY INVISIBLE (-2050 2575);
FORCEPROP 1 LAST COMMENT_BODY TRUE
J 0
(-2400 2600);
DISPLAY 0.872340 (-2400 2600);
PAINT GREEN (-2400 2600);
DISPLAY INVISIBLE (-2400 2600);
FORCEPROP 2 LAST PATH I104
J 0
(-2175 2750);
DISPLAY 0.680851 (-2175 2750);
DISPLAY INVISIBLE (-2175 2750);
FORCEADD OFFPAGE..2
(-2375 2500);
FORCEPROP 2 LAST $XR0 198 
J 0
(-2186 2500);
DISPLAY 0.638298 (-2186 2500);
PAINT MONO (-2186 2500);
FORCEPROP 2 LAST CDS_LIB standard
J 0
(-2375 2500);
DISPLAY INVISIBLE (-2375 2500);
FORCEPROP 1 LAST OFFPAGE TRUE
J 0
(-2050 2375);
DISPLAY 0.872340 (-2050 2375);
PAINT GREEN (-2050 2375);
DISPLAY INVISIBLE (-2050 2375);
FORCEPROP 1 LAST COMMENT_BODY TRUE
J 0
(-2420 2405);
DISPLAY 0.872340 (-2420 2405);
PAINT GREEN (-2420 2405);
DISPLAY INVISIBLE (-2420 2405);
FORCEPROP 2 LAST PATH I105
J 0
(-2175 2550);
DISPLAY 0.680851 (-2175 2550);
DISPLAY INVISIBLE (-2175 2550);
FORCEADD UNIVERSAL_GND..1
(-2150 2875);
FORCEPROP 3 LASTPIN (-2150 2925) SIG_NAME GND\g
J 0
(-2140 2935);
DISPLAY 0.659574 (-2140 2935);
PAINT MONO (-2140 2935);
DISPLAY INVISIBLE (-2140 2935);
FORCEPROP 2 LAST CDS_LIB pure_quanta_power
J 0
(-2150 2875);
DISPLAY INVISIBLE (-2150 2875);
FORCEPROP 1 LAST HDL_POWER GND
J 1
(-2125 2800);
DISPLAY 0.872340 (-2125 2800);
PAINT GREEN (-2125 2800);
DISPLAY INVISIBLE (-2125 2800);
FORCEPROP 1 LAST PATH I106
J 0
(-2075 2875);
DISPLAY 0.872340 (-2075 2875);
PAINT AQUA (-2075 2875);
DISPLAY INVISIBLE (-2075 2875);
FORCEADD Q_RES..1
(-2500 3000);
FORCEPROP 1 LAST LOCATION PR441
J 0
(-2550 3050);
DISPLAY 0.489362 (-2550 3050);
PAINT SKYBLUE (-2550 3050);
FORCEPROP 0 LAST $SEC 1
J 0
(-2550 3075);
DISPLAY 0.680851 (-2550 3075);
PAINT MONO (-2550 3075);
DISPLAY INVISIBLE (-2550 3075);
FORCEPROP 0 LAST CDS_SEC 1
J 0
(-2550 3075);
DISPLAY 0.680851 (-2550 3075);
DISPLAY INVISIBLE (-2550 3075);
FORCEPROP 1 LASTPIN (-2600 3000) $PN 1
J 0
(-2588 3012);
DISPLAY 0.787234 (-2588 3012);
PAINT MONO (-2588 3012);
DISPLAY INVISIBLE (-2588 3012);
FORCEPROP 1 LASTPIN (-2400 3000) $PN 2
J 0
(-2438 3012);
DISPLAY 0.787234 (-2438 3012);
PAINT MONO (-2438 3012);
DISPLAY INVISIBLE (-2438 3012);
FORCEPROP 1 LAST MATERIAL CHIP
J 0
(-2825 2950);
DISPLAY 0.489362 (-2825 2950);
PAINT SKYBLUE (-2825 2950);
FORCEPROP 1 LAST WATTAGE 1/16W
J 2
(-2575 2950);
DISPLAY 0.489362 (-2575 2950);
PAINT SKYBLUE (-2575 2950);
FORCEPROP 1 LAST VALUE 0
J 2
(-2500 2950);
DISPLAY 0.489362 (-2500 2950);
PAINT SKYBLUE (-2500 2950);
FORCEPROP 1 LAST TOLERANCE 5%
J 0
(-2475 2950);
DISPLAY 0.489362 (-2475 2950);
PAINT SKYBLUE (-2475 2950);
FORCEPROP 1 LAST PACK_TYPE 0402LF
J 0
(-2400 2950);
DISPLAY 0.489362 (-2400 2950);
PAINT SKYBLUE (-2400 2950);
FORCEPROP 2 LAST CDS_LIB pure_quanta
J 0
(-2500 3000);
DISPLAY INVISIBLE (-2500 3000);
FORCEPROP 1 LAST PATH I107
J 0
(-2550 3150);
DISPLAY 0.978723 (-2550 3150);
PAINT WHITE (-2550 3150);
DISPLAY INVISIBLE (-2550 3150);
FORCEPROP 1 LAST PART_NUMBER CS00002JB13
J 0
(-3175 2950);
DISPLAY 0.489362 (-3175 2950);
PAINT SKYBLUE (-3175 2950);
DISPLAY INVISIBLE (-3175 2950);
FORCEADD Q_RES..1
(-2500 3300);
FORCEPROP 1 LAST LOCATION PR440
J 0
(-2550 3350);
DISPLAY 0.489362 (-2550 3350);
PAINT SKYBLUE (-2550 3350);
FORCEPROP 0 LAST $SEC 1
J 0
(-2550 3375);
DISPLAY 0.680851 (-2550 3375);
PAINT MONO (-2550 3375);
DISPLAY INVISIBLE (-2550 3375);
FORCEPROP 0 LAST CDS_SEC 1
J 0
(-2550 3375);
DISPLAY 1.021277 (-2550 3375);
DISPLAY INVISIBLE (-2550 3375);
FORCEPROP 1 LASTPIN (-2600 3300) $PN 1
J 0
(-2588 3312);
DISPLAY 0.489362 (-2588 3312);
PAINT MONO (-2588 3312);
FORCEPROP 1 LASTPIN (-2400 3300) $PN 2
J 0
(-2438 3312);
DISPLAY 0.489362 (-2438 3312);
PAINT MONO (-2438 3312);
FORCEPROP 1 LAST WATTAGE 1/16W
J 2
(-2575 3250);
DISPLAY 0.489362 (-2575 3250);
PAINT SKYBLUE (-2575 3250);
FORCEPROP 1 LAST VALUE 0
J 2
(-2500 3250);
DISPLAY 0.489362 (-2500 3250);
PAINT SKYBLUE (-2500 3250);
FORCEPROP 1 LAST TOLERANCE 5%
J 0
(-2475 3250);
DISPLAY 0.489362 (-2475 3250);
PAINT SKYBLUE (-2475 3250);
FORCEPROP 1 LAST PACK_TYPE 0402LF
J 0
(-2400 3250);
DISPLAY 0.489362 (-2400 3250);
PAINT SKYBLUE (-2400 3250);
FORCEPROP 1 LAST MATERIAL CHIP
J 0
(-2825 3250);
DISPLAY 0.489362 (-2825 3250);
PAINT SKYBLUE (-2825 3250);
FORCEPROP 2 LAST CDS_LIB pure_quanta
J 0
(-2500 3300);
DISPLAY INVISIBLE (-2500 3300);
FORCEPROP 1 LAST PATH I108
J 0
(-2550 3450);
DISPLAY 0.978723 (-2550 3450);
PAINT WHITE (-2550 3450);
DISPLAY INVISIBLE (-2550 3450);
FORCEPROP 1 LAST PART_NUMBER CS00002JB13
J 0
(-3175 3250);
DISPLAY 0.489362 (-3175 3250);
PAINT SKYBLUE (-3175 3250);
DISPLAY INVISIBLE (-3175 3250);
FORCEADD UNIVERSAL_GND..1
(-2150 3450);
FORCEPROP 3 LASTPIN (-2150 3500) SIG_NAME GND\g
J 0
(-2140 3510);
DISPLAY 0.659574 (-2140 3510);
PAINT MONO (-2140 3510);
DISPLAY INVISIBLE (-2140 3510);
FORCEPROP 2 LAST CDS_LIB pure_quanta_power
J 0
(-2150 3450);
DISPLAY INVISIBLE (-2150 3450);
FORCEPROP 1 LAST HDL_POWER GND
J 1
(-2125 3375);
DISPLAY 0.872340 (-2125 3375);
PAINT GREEN (-2125 3375);
DISPLAY INVISIBLE (-2125 3375);
FORCEPROP 1 LAST PATH I109
J 0
(-2075 3450);
DISPLAY 0.872340 (-2075 3450);
PAINT AQUA (-2075 3450);
DISPLAY INVISIBLE (-2075 3450);
FORCEADD VCC_CORE..1
(-7900 6675);
FORCEPROP 3 LASTPIN (-7900 6625) SIG_NAME PVDD18_S5_P0\g
J 0
(-7890 6635);
DISPLAY 0.659574 (-7890 6635);
PAINT MONO (-7890 6635);
DISPLAY INVISIBLE (-7890 6635);
FORCEPROP 1 LAST HDL_POWER PVDD18_S5_P0
J 1
(-7900 6725);
DISPLAY 0.489362 (-7900 6725);
PAINT GREEN (-7900 6725);
FORCEPROP 2 LAST CDS_LIB pure_quanta_power
J 0
(-7900 6675);
DISPLAY INVISIBLE (-7900 6675);
FORCEPROP 1 LAST PATH I11
J 0
(-7850 6700);
DISPLAY 0.872340 (-7850 6700);
PAINT AQUA (-7850 6700);
DISPLAY INVISIBLE (-7850 6700);
FORCEADD UNIVERSAL_GND..1
(-2150 3150);
FORCEPROP 3 LASTPIN (-2150 3200) SIG_NAME GND\g
J 0
(-2140 3210);
DISPLAY 0.659574 (-2140 3210);
PAINT MONO (-2140 3210);
DISPLAY INVISIBLE (-2140 3210);
FORCEPROP 2 LAST CDS_LIB pure_quanta_power
J 0
(-2150 3150);
DISPLAY INVISIBLE (-2150 3150);
FORCEPROP 1 LAST HDL_POWER GND
J 1
(-2125 3075);
DISPLAY 0.872340 (-2125 3075);
PAINT GREEN (-2125 3075);
DISPLAY INVISIBLE (-2125 3075);
FORCEPROP 1 LAST PATH I110
J 0
(-2075 3150);
DISPLAY 0.872340 (-2075 3150);
PAINT AQUA (-2075 3150);
DISPLAY INVISIBLE (-2075 3150);
FORCEADD Q_RES..1
(-2500 3600);
FORCEPROP 1 LAST LOCATION PR531
J 0
(-2550 3650);
DISPLAY 0.489362 (-2550 3650);
PAINT SKYBLUE (-2550 3650);
FORCEPROP 0 LAST $SEC 1
J 0
(-2550 3675);
DISPLAY 0.680851 (-2550 3675);
PAINT MONO (-2550 3675);
DISPLAY INVISIBLE (-2550 3675);
FORCEPROP 0 LAST CDS_SEC 1
J 0
(-2550 3675);
DISPLAY 1.021277 (-2550 3675);
DISPLAY INVISIBLE (-2550 3675);
FORCEPROP 1 LASTPIN (-2600 3600) $PN 1
J 0
(-2588 3612);
DISPLAY 0.489362 (-2588 3612);
PAINT MONO (-2588 3612);
FORCEPROP 1 LASTPIN (-2400 3600) $PN 2
J 0
(-2438 3612);
DISPLAY 0.489362 (-2438 3612);
PAINT MONO (-2438 3612);
FORCEPROP 1 LAST PACK_TYPE 0402LF
J 0
(-2400 3550);
DISPLAY 0.489362 (-2400 3550);
PAINT SKYBLUE (-2400 3550);
FORCEPROP 1 LAST VALUE 0
J 2
(-2500 3550);
DISPLAY 0.489362 (-2500 3550);
PAINT SKYBLUE (-2500 3550);
FORCEPROP 1 LAST WATTAGE 1/16W
J 2
(-2575 3550);
DISPLAY 0.489362 (-2575 3550);
PAINT SKYBLUE (-2575 3550);
FORCEPROP 1 LAST TOLERANCE 5%
J 0
(-2475 3550);
DISPLAY 0.489362 (-2475 3550);
PAINT SKYBLUE (-2475 3550);
FORCEPROP 1 LAST MATERIAL CHIP
J 0
(-2825 3550);
DISPLAY 0.489362 (-2825 3550);
PAINT SKYBLUE (-2825 3550);
FORCEPROP 2 LAST CDS_LIB pure_quanta
J 0
(-2500 3600);
DISPLAY INVISIBLE (-2500 3600);
FORCEPROP 1 LAST PATH I111
J 0
(-2550 3750);
DISPLAY 0.978723 (-2550 3750);
PAINT WHITE (-2550 3750);
DISPLAY INVISIBLE (-2550 3750);
FORCEPROP 1 LAST PART_NUMBER CS00002JB13
J 0
(-3175 3550);
DISPLAY 0.489362 (-3175 3550);
PAINT SKYBLUE (-3175 3550);
DISPLAY INVISIBLE (-3175 3550);
FORCEADD OFFPAGE..4
(-2375 3900);
FORCEPROP 2 LAST $XR0 196 
J 0
(-2189 3900);
DISPLAY 0.638298 (-2189 3900);
PAINT MONO (-2189 3900);
FORCEPROP 2 LAST CDS_LIB standard
J 0
(-2375 3900);
DISPLAY INVISIBLE (-2375 3900);
FORCEPROP 1 LAST OFFPAGE TRUE
J 0
(-2050 3775);
DISPLAY 0.872340 (-2050 3775);
PAINT GREEN (-2050 3775);
DISPLAY INVISIBLE (-2050 3775);
FORCEPROP 1 LAST COMMENT_BODY TRUE
J 0
(-2400 3800);
DISPLAY 0.872340 (-2400 3800);
PAINT GREEN (-2400 3800);
DISPLAY INVISIBLE (-2400 3800);
FORCEPROP 2 LAST PATH I112
J 0
(-2175 3950);
DISPLAY 0.680851 (-2175 3950);
DISPLAY INVISIBLE (-2175 3950);
FORCEADD OFFPAGE..2
(-2375 4000);
FORCEPROP 2 LAST $XR0 196 
J 0
(-2186 4000);
DISPLAY 0.638298 (-2186 4000);
PAINT MONO (-2186 4000);
FORCEPROP 2 LAST CDS_LIB standard
J 0
(-2375 4000);
DISPLAY INVISIBLE (-2375 4000);
FORCEPROP 1 LAST OFFPAGE TRUE
J 0
(-2050 3875);
DISPLAY 0.872340 (-2050 3875);
PAINT GREEN (-2050 3875);
DISPLAY INVISIBLE (-2050 3875);
FORCEPROP 1 LAST COMMENT_BODY TRUE
J 0
(-2420 3905);
DISPLAY 0.872340 (-2420 3905);
PAINT GREEN (-2420 3905);
DISPLAY INVISIBLE (-2420 3905);
FORCEPROP 2 LAST PATH I113
J 0
(-2175 4050);
DISPLAY 0.680851 (-2175 4050);
DISPLAY INVISIBLE (-2175 4050);
FORCEADD OFFPAGE..2
(-2375 4300);
FORCEPROP 2 LAST $XR0 196 
J 0
(-2186 4300);
DISPLAY 0.638298 (-2186 4300);
PAINT MONO (-2186 4300);
FORCEPROP 2 LAST CDS_LIB standard
J 0
(-2375 4300);
DISPLAY INVISIBLE (-2375 4300);
FORCEPROP 1 LAST OFFPAGE TRUE
J 0
(-2050 4175);
DISPLAY 0.872340 (-2050 4175);
PAINT GREEN (-2050 4175);
DISPLAY INVISIBLE (-2050 4175);
FORCEPROP 1 LAST COMMENT_BODY TRUE
J 0
(-2420 4205);
DISPLAY 0.872340 (-2420 4205);
PAINT GREEN (-2420 4205);
DISPLAY INVISIBLE (-2420 4205);
FORCEPROP 2 LAST PATH I114
J 0
(-2175 4350);
DISPLAY 0.680851 (-2175 4350);
DISPLAY INVISIBLE (-2175 4350);
FORCEADD OFFPAGE..4
(-2375 4200);
FORCEPROP 2 LAST $XR0 196 
J 0
(-2189 4200);
DISPLAY 0.638298 (-2189 4200);
PAINT MONO (-2189 4200);
FORCEPROP 2 LAST CDS_LIB standard
J 0
(-2375 4200);
DISPLAY INVISIBLE (-2375 4200);
FORCEPROP 1 LAST OFFPAGE TRUE
J 0
(-2050 4075);
DISPLAY 0.872340 (-2050 4075);
PAINT GREEN (-2050 4075);
DISPLAY INVISIBLE (-2050 4075);
FORCEPROP 1 LAST COMMENT_BODY TRUE
J 0
(-2400 4100);
DISPLAY 0.872340 (-2400 4100);
PAINT GREEN (-2400 4100);
DISPLAY INVISIBLE (-2400 4100);
FORCEPROP 2 LAST PATH I115
J 0
(-2175 4250);
DISPLAY 0.680851 (-2175 4250);
DISPLAY INVISIBLE (-2175 4250);
FORCEADD OFFPAGE..4
(-2375 4500);
FORCEPROP 2 LAST $XR0 195 
J 0
(-2189 4500);
DISPLAY 0.638298 (-2189 4500);
PAINT MONO (-2189 4500);
FORCEPROP 2 LAST CDS_LIB standard
J 0
(-2375 4500);
DISPLAY INVISIBLE (-2375 4500);
FORCEPROP 1 LAST OFFPAGE TRUE
J 0
(-2050 4375);
DISPLAY 0.872340 (-2050 4375);
PAINT GREEN (-2050 4375);
DISPLAY INVISIBLE (-2050 4375);
FORCEPROP 1 LAST COMMENT_BODY TRUE
J 0
(-2400 4400);
DISPLAY 0.872340 (-2400 4400);
PAINT GREEN (-2400 4400);
DISPLAY INVISIBLE (-2400 4400);
FORCEPROP 2 LAST PATH I116
J 0
(-2175 4550);
DISPLAY 0.680851 (-2175 4550);
DISPLAY INVISIBLE (-2175 4550);
FORCEADD UNIVERSAL_GND..1
(-2775 5825);
FORCEPROP 3 LASTPIN (-2775 5875) SIG_NAME GND\g
J 0
(-2765 5885);
DISPLAY 0.659574 (-2765 5885);
PAINT MONO (-2765 5885);
DISPLAY INVISIBLE (-2765 5885);
FORCEPROP 2 LAST CDS_LIB pure_quanta_power
J 0
(-2775 5825);
DISPLAY INVISIBLE (-2775 5825);
FORCEPROP 1 LAST HDL_POWER GND
J 1
(-2750 5750);
DISPLAY 0.872340 (-2750 5750);
PAINT GREEN (-2750 5750);
DISPLAY INVISIBLE (-2750 5750);
FORCEPROP 1 LAST PATH I117
J 0
(-2700 5825);
DISPLAY 0.872340 (-2700 5825);
PAINT AQUA (-2700 5825);
DISPLAY INVISIBLE (-2700 5825);
FORCEADD Q_CAP..1
(-2775 6050);
FORCEPROP 1 LAST LOCATION PC13
J 0
(-2725 6150);
DISPLAY 0.489362 (-2725 6150);
PAINT SKYBLUE (-2725 6150);
FORCEPROP 0 LAST $SEC 1
J 0
(-2725 6175);
DISPLAY 0.680851 (-2725 6175);
PAINT MONO (-2725 6175);
DISPLAY INVISIBLE (-2725 6175);
FORCEPROP 0 LAST CDS_SEC 1
J 0
(-2725 6175);
DISPLAY 1.021277 (-2725 6175);
DISPLAY INVISIBLE (-2725 6175);
FORCEPROP 1 LASTPIN (-2775 6150) $PN 1
J 0
(-2765 6130);
DISPLAY 0.489362 (-2765 6130);
PAINT MONO (-2765 6130);
FORCEPROP 1 LASTPIN (-2775 5950) $PN 2
J 0
(-2765 5930);
DISPLAY 0.489362 (-2765 5930);
PAINT MONO (-2765 5930);
FORCEPROP 1 LAST MATERIAL X7R
J 0
(-2725 5950);
DISPLAY 0.489362 (-2725 5950);
PAINT SKYBLUE (-2725 5950);
FORCEPROP 1 LAST TOLERANCE 10%
J 0
(-2725 6000);
DISPLAY 0.489362 (-2725 6000);
PAINT SKYBLUE (-2725 6000);
FORCEPROP 1 LAST VOLTAGE 25V
J 0
(-2725 6050);
DISPLAY 0.489362 (-2725 6050);
PAINT SKYBLUE (-2725 6050);
FORCEPROP 1 LAST PACK_TYPE 0402
J 0
(-2725 5850);
DISPLAY 0.489362 (-2725 5850);
PAINT SKYBLUE (-2725 5850);
FORCEPROP 1 LAST VALUE 0.1UF
J 0
(-2725 6100);
DISPLAY 0.489362 (-2725 6100);
PAINT SKYBLUE (-2725 6100);
FORCEPROP 2 LAST CDS_LIB pure_quanta
J 0
(-2775 6050);
DISPLAY INVISIBLE (-2775 6050);
FORCEPROP 1 LAST PATH I118
J 0
(-2725 6200);
DISPLAY 0.978723 (-2725 6200);
PAINT WHITE (-2725 6200);
DISPLAY INVISIBLE (-2725 6200);
FORCEPROP 1 LAST PART_NUMBER CH4104K1B00
J 0
(-2725 5900);
DISPLAY 0.489362 (-2725 5900);
PAINT SKYBLUE (-2725 5900);
DISPLAY INVISIBLE (-2725 5900);
FORCEADD UNIVERSAL_GND..1
(-2775 6275);
FORCEPROP 3 LASTPIN (-2775 6325) SIG_NAME GND\g
J 0
(-2765 6335);
DISPLAY 0.659574 (-2765 6335);
PAINT MONO (-2765 6335);
DISPLAY INVISIBLE (-2765 6335);
FORCEPROP 2 LAST CDS_LIB pure_quanta_power
J 0
(-2775 6275);
DISPLAY INVISIBLE (-2775 6275);
FORCEPROP 1 LAST HDL_POWER GND
J 1
(-2750 6200);
DISPLAY 0.872340 (-2750 6200);
PAINT GREEN (-2750 6200);
DISPLAY INVISIBLE (-2750 6200);
FORCEPROP 1 LAST PATH I119
J 0
(-2700 6275);
DISPLAY 0.872340 (-2700 6275);
PAINT AQUA (-2700 6275);
DISPLAY INVISIBLE (-2700 6275);
FORCEADD UNIVERSAL_GND..1
(-7675 1350);
FORCEPROP 3 LASTPIN (-7675 1400) SIG_NAME GND\g
J 0
(-7665 1410);
DISPLAY 0.659574 (-7665 1410);
PAINT MONO (-7665 1410);
DISPLAY INVISIBLE (-7665 1410);
FORCEPROP 2 LAST CDS_LIB pure_quanta_power
J 0
(-7675 1350);
DISPLAY INVISIBLE (-7675 1350);
FORCEPROP 1 LAST HDL_POWER GND
J 1
(-7650 1275);
DISPLAY 0.872340 (-7650 1275);
PAINT GREEN (-7650 1275);
DISPLAY INVISIBLE (-7650 1275);
FORCEPROP 1 LAST PATH I12
J 0
(-7600 1350);
DISPLAY 0.872340 (-7600 1350);
PAINT AQUA (-7600 1350);
DISPLAY INVISIBLE (-7600 1350);
FORCEADD Q_CAP..1
(-2775 6525);
FORCEPROP 1 LAST LOCATION PC12
J 0
(-2725 6625);
DISPLAY 0.489362 (-2725 6625);
PAINT SKYBLUE (-2725 6625);
FORCEPROP 0 LAST $SEC 1
J 0
(-2725 6650);
DISPLAY 0.680851 (-2725 6650);
PAINT MONO (-2725 6650);
DISPLAY INVISIBLE (-2725 6650);
FORCEPROP 0 LAST CDS_SEC 1
J 0
(-2725 6650);
DISPLAY 1.021277 (-2725 6650);
DISPLAY INVISIBLE (-2725 6650);
FORCEPROP 1 LASTPIN (-2775 6625) $PN 1
J 0
(-2765 6605);
DISPLAY 0.489362 (-2765 6605);
PAINT MONO (-2765 6605);
FORCEPROP 1 LASTPIN (-2775 6425) $PN 2
J 0
(-2765 6405);
DISPLAY 0.489362 (-2765 6405);
PAINT MONO (-2765 6405);
FORCEPROP 1 LAST MATERIAL X7R
J 0
(-2725 6425);
DISPLAY 0.489362 (-2725 6425);
PAINT SKYBLUE (-2725 6425);
FORCEPROP 1 LAST VALUE 0.1UF
J 0
(-2725 6575);
DISPLAY 0.489362 (-2725 6575);
PAINT SKYBLUE (-2725 6575);
FORCEPROP 1 LAST PACK_TYPE 0402
J 0
(-2725 6325);
DISPLAY 0.489362 (-2725 6325);
PAINT SKYBLUE (-2725 6325);
FORCEPROP 1 LAST TOLERANCE 10%
J 0
(-2725 6475);
DISPLAY 0.489362 (-2725 6475);
PAINT SKYBLUE (-2725 6475);
FORCEPROP 1 LAST VOLTAGE 25V
J 0
(-2725 6525);
DISPLAY 0.489362 (-2725 6525);
PAINT SKYBLUE (-2725 6525);
FORCEPROP 2 LAST CDS_LIB pure_quanta
J 0
(-2775 6525);
DISPLAY INVISIBLE (-2775 6525);
FORCEPROP 1 LAST PATH I120
J 0
(-2725 6675);
DISPLAY 0.978723 (-2725 6675);
PAINT WHITE (-2725 6675);
DISPLAY INVISIBLE (-2725 6675);
FORCEPROP 1 LAST PART_NUMBER CH4104K1B00
J 0
(-2725 6375);
DISPLAY 0.489362 (-2725 6375);
PAINT SKYBLUE (-2725 6375);
DISPLAY INVISIBLE (-2725 6375);
FORCEADD OFFPAGE..2
(-2375 4600);
FORCEPROP 2 LAST $XR0 195 
J 0
(-2186 4600);
DISPLAY 0.638298 (-2186 4600);
PAINT MONO (-2186 4600);
FORCEPROP 2 LAST CDS_LIB standard
J 0
(-2375 4600);
DISPLAY INVISIBLE (-2375 4600);
FORCEPROP 1 LAST OFFPAGE TRUE
J 0
(-2050 4475);
DISPLAY 0.872340 (-2050 4475);
PAINT GREEN (-2050 4475);
DISPLAY INVISIBLE (-2050 4475);
FORCEPROP 1 LAST COMMENT_BODY TRUE
J 0
(-2420 4505);
DISPLAY 0.872340 (-2420 4505);
PAINT GREEN (-2420 4505);
DISPLAY INVISIBLE (-2420 4505);
FORCEPROP 2 LAST PATH I121
J 0
(-2175 4650);
DISPLAY 0.680851 (-2175 4650);
DISPLAY INVISIBLE (-2175 4650);
FORCEADD OFFPAGE..4
(-2375 4800);
FORCEPROP 2 LAST $XR0 195 
J 0
(-2189 4800);
DISPLAY 0.638298 (-2189 4800);
PAINT MONO (-2189 4800);
FORCEPROP 2 LAST CDS_LIB standard
J 0
(-2375 4800);
DISPLAY INVISIBLE (-2375 4800);
FORCEPROP 1 LAST OFFPAGE TRUE
J 0
(-2050 4675);
DISPLAY 0.872340 (-2050 4675);
PAINT GREEN (-2050 4675);
DISPLAY INVISIBLE (-2050 4675);
FORCEPROP 1 LAST COMMENT_BODY TRUE
J 0
(-2400 4700);
DISPLAY 0.872340 (-2400 4700);
PAINT GREEN (-2400 4700);
DISPLAY INVISIBLE (-2400 4700);
FORCEPROP 2 LAST PATH I122
J 0
(-2175 4850);
DISPLAY 0.680851 (-2175 4850);
DISPLAY INVISIBLE (-2175 4850);
FORCEADD OFFPAGE..2
(-2375 4900);
FORCEPROP 2 LAST $XR0 195 
J 0
(-2186 4900);
DISPLAY 0.638298 (-2186 4900);
PAINT MONO (-2186 4900);
FORCEPROP 2 LAST CDS_LIB standard
J 0
(-2375 4900);
DISPLAY INVISIBLE (-2375 4900);
FORCEPROP 1 LAST OFFPAGE TRUE
J 0
(-2050 4775);
DISPLAY 0.872340 (-2050 4775);
PAINT GREEN (-2050 4775);
DISPLAY INVISIBLE (-2050 4775);
FORCEPROP 1 LAST COMMENT_BODY TRUE
J 0
(-2420 4805);
DISPLAY 0.872340 (-2420 4805);
PAINT GREEN (-2420 4805);
DISPLAY INVISIBLE (-2420 4805);
FORCEPROP 2 LAST PATH I123
J 0
(-2175 4950);
DISPLAY 0.680851 (-2175 4950);
DISPLAY INVISIBLE (-2175 4950);
FORCEADD OFFPAGE..4
(-2375 5100);
FORCEPROP 2 LAST $XR0 194 
J 0
(-2189 5100);
DISPLAY 0.638298 (-2189 5100);
PAINT MONO (-2189 5100);
FORCEPROP 2 LAST CDS_LIB standard
J 0
(-2375 5100);
DISPLAY INVISIBLE (-2375 5100);
FORCEPROP 1 LAST OFFPAGE TRUE
J 0
(-2050 4975);
DISPLAY 0.872340 (-2050 4975);
PAINT GREEN (-2050 4975);
DISPLAY INVISIBLE (-2050 4975);
FORCEPROP 1 LAST COMMENT_BODY TRUE
J 0
(-2400 5000);
DISPLAY 0.872340 (-2400 5000);
PAINT GREEN (-2400 5000);
DISPLAY INVISIBLE (-2400 5000);
FORCEPROP 2 LAST PATH I124
J 0
(-2175 5150);
DISPLAY 0.680851 (-2175 5150);
DISPLAY INVISIBLE (-2175 5150);
FORCEADD OFFPAGE..2
(-2375 5200);
FORCEPROP 2 LAST $XR0 194 
J 0
(-2186 5200);
DISPLAY 0.638298 (-2186 5200);
PAINT MONO (-2186 5200);
FORCEPROP 2 LAST CDS_LIB standard
J 0
(-2375 5200);
DISPLAY INVISIBLE (-2375 5200);
FORCEPROP 1 LAST OFFPAGE TRUE
J 0
(-2050 5075);
DISPLAY 0.872340 (-2050 5075);
PAINT GREEN (-2050 5075);
DISPLAY INVISIBLE (-2050 5075);
FORCEPROP 1 LAST COMMENT_BODY TRUE
J 0
(-2420 5105);
DISPLAY 0.872340 (-2420 5105);
PAINT GREEN (-2420 5105);
DISPLAY INVISIBLE (-2420 5105);
FORCEPROP 2 LAST PATH I125
J 0
(-2175 5250);
DISPLAY 0.680851 (-2175 5250);
DISPLAY INVISIBLE (-2175 5250);
FORCEADD OFFPAGE..4
(-2375 5400);
FORCEPROP 2 LAST $XR0 194 
J 0
(-2189 5400);
DISPLAY 0.638298 (-2189 5400);
PAINT MONO (-2189 5400);
FORCEPROP 2 LAST CDS_LIB standard
J 0
(-2375 5400);
DISPLAY INVISIBLE (-2375 5400);
FORCEPROP 1 LAST OFFPAGE TRUE
J 0
(-2050 5275);
DISPLAY 0.872340 (-2050 5275);
PAINT GREEN (-2050 5275);
DISPLAY INVISIBLE (-2050 5275);
FORCEPROP 1 LAST COMMENT_BODY TRUE
J 0
(-2400 5300);
DISPLAY 0.872340 (-2400 5300);
PAINT GREEN (-2400 5300);
DISPLAY INVISIBLE (-2400 5300);
FORCEPROP 2 LAST PATH I126
J 0
(-2175 5450);
DISPLAY 0.680851 (-2175 5450);
DISPLAY INVISIBLE (-2175 5450);
FORCEADD OFFPAGE..2
(-2375 5500);
FORCEPROP 2 LAST $XR0 194 
J 0
(-2186 5500);
DISPLAY 0.638298 (-2186 5500);
PAINT MONO (-2186 5500);
FORCEPROP 2 LAST CDS_LIB standard
J 0
(-2375 5500);
DISPLAY INVISIBLE (-2375 5500);
FORCEPROP 1 LAST OFFPAGE TRUE
J 0
(-2050 5375);
DISPLAY 0.872340 (-2050 5375);
PAINT GREEN (-2050 5375);
DISPLAY INVISIBLE (-2050 5375);
FORCEPROP 1 LAST COMMENT_BODY TRUE
J 0
(-2420 5405);
DISPLAY 0.872340 (-2420 5405);
PAINT GREEN (-2420 5405);
DISPLAY INVISIBLE (-2420 5405);
FORCEPROP 2 LAST PATH I127
J 0
(-2175 5550);
DISPLAY 0.680851 (-2175 5550);
DISPLAY INVISIBLE (-2175 5550);
FORCEADD UNIVERSAL_GND..1
(-2500 5825);
FORCEPROP 3 LASTPIN (-2500 5875) SIG_NAME GND\g
J 0
(-2490 5885);
DISPLAY 0.659574 (-2490 5885);
PAINT MONO (-2490 5885);
DISPLAY INVISIBLE (-2490 5885);
FORCEPROP 2 LAST CDS_LIB pure_quanta_power
J 0
(-2500 5825);
DISPLAY INVISIBLE (-2500 5825);
FORCEPROP 1 LAST HDL_POWER GND
J 1
(-2475 5750);
DISPLAY 0.872340 (-2475 5750);
PAINT GREEN (-2475 5750);
DISPLAY INVISIBLE (-2475 5750);
FORCEPROP 1 LAST PATH I128
J 0
(-2425 5825);
DISPLAY 0.872340 (-2425 5825);
PAINT AQUA (-2425 5825);
DISPLAY INVISIBLE (-2425 5825);
FORCEADD Q_CAP..1
(-2500 6050);
FORCEPROP 1 LAST LOCATION PC470
J 0
(-2450 6150);
DISPLAY 0.489362 (-2450 6150);
PAINT SKYBLUE (-2450 6150);
FORCEPROP 0 LAST $SEC 1
J 0
(-2450 6175);
DISPLAY 0.680851 (-2450 6175);
PAINT MONO (-2450 6175);
DISPLAY INVISIBLE (-2450 6175);
FORCEPROP 0 LAST CDS_SEC 1
J 0
(-2450 6175);
DISPLAY 1.021277 (-2450 6175);
DISPLAY INVISIBLE (-2450 6175);
FORCEPROP 1 LASTPIN (-2500 6150) $PN 1
J 0
(-2490 6130);
DISPLAY 0.489362 (-2490 6130);
PAINT MONO (-2490 6130);
FORCEPROP 1 LASTPIN (-2500 5950) $PN 2
J 0
(-2490 5930);
DISPLAY 0.489362 (-2490 5930);
PAINT MONO (-2490 5930);
FORCEPROP 1 LAST PACK_TYPE C0402
J 0
(-2450 5850);
DISPLAY 0.489362 (-2450 5850);
PAINT SKYBLUE (-2450 5850);
FORCEPROP 1 LAST VOLTAGE 6.3V
J 0
(-2450 6050);
DISPLAY 0.489362 (-2450 6050);
PAINT SKYBLUE (-2450 6050);
FORCEPROP 1 LAST VALUE 10UF
J 0
(-2450 6100);
DISPLAY 0.489362 (-2450 6100);
PAINT SKYBLUE (-2450 6100);
FORCEPROP 1 LAST TOLERANCE 20%
J 0
(-2450 6000);
DISPLAY 0.489362 (-2450 6000);
PAINT SKYBLUE (-2450 6000);
FORCEPROP 1 LAST MATERIAL X6S
J 0
(-2450 5950);
DISPLAY 0.489362 (-2450 5950);
PAINT SKYBLUE (-2450 5950);
FORCEPROP 2 LAST CDS_LIB pure_quanta
J 0
(-2500 6050);
DISPLAY INVISIBLE (-2500 6050);
FORCEPROP 1 LAST PATH I129
J 0
(-2450 6200);
DISPLAY 0.978723 (-2450 6200);
PAINT WHITE (-2450 6200);
DISPLAY INVISIBLE (-2450 6200);
FORCEPROP 1 LAST PART_NUMBER CH6101MEB03
J 0
(-2450 5900);
DISPLAY 0.489362 (-2450 5900);
PAINT SKYBLUE (-2450 5900);
DISPLAY INVISIBLE (-2450 5900);
FORCEADD Q_CAP..1
(-7675 1600);
FORCEPROP 1 LAST LOCATION C461
J 0
(-7625 1700);
DISPLAY 0.489362 (-7625 1700);
PAINT SKYBLUE (-7625 1700);
FORCEPROP 0 LAST $SEC 1
J 0
(-7625 1725);
DISPLAY 0.680851 (-7625 1725);
PAINT MONO (-7625 1725);
DISPLAY INVISIBLE (-7625 1725);
FORCEPROP 0 LAST CDS_SEC 1
J 0
(-7625 1725);
DISPLAY 1.021277 (-7625 1725);
DISPLAY INVISIBLE (-7625 1725);
FORCEPROP 1 LASTPIN (-7675 1700) $PN 1
J 0
(-7665 1680);
DISPLAY 0.489362 (-7665 1680);
PAINT MONO (-7665 1680);
FORCEPROP 1 LASTPIN (-7675 1500) $PN 2
J 0
(-7665 1480);
DISPLAY 0.489362 (-7665 1480);
PAINT MONO (-7665 1480);
FORCEPROP 1 LAST TOLERANCE 5%
J 0
(-7625 1550);
DISPLAY 0.489362 (-7625 1550);
PAINT SKYBLUE (-7625 1550);
FORCEPROP 1 LAST MATERIAL X7R
J 0
(-7625 1500);
DISPLAY 0.489362 (-7625 1500);
PAINT SKYBLUE (-7625 1500);
FORCEPROP 1 LAST VOLTAGE 50V
J 0
(-7625 1600);
DISPLAY 0.489362 (-7625 1600);
PAINT SKYBLUE (-7625 1600);
FORCEPROP 1 LAST VALUE 1000PF
J 0
(-7625 1650);
DISPLAY 0.489362 (-7625 1650);
PAINT SKYBLUE (-7625 1650);
FORCEPROP 1 LAST PACK_TYPE 0402
J 0
(-7625 1400);
DISPLAY 0.489362 (-7625 1400);
PAINT SKYBLUE (-7625 1400);
FORCEPROP 2 LAST CDS_LIB pure_quanta
J 0
(-7675 1600);
DISPLAY INVISIBLE (-7675 1600);
FORCEPROP 1 LAST PATH I13
J 0
(-7625 1750);
DISPLAY 0.978723 (-7625 1750);
PAINT WHITE (-7625 1750);
DISPLAY INVISIBLE (-7625 1750);
FORCEPROP 1 LAST PART_NUMBER TMP_QCH21006JB10
J 0
(-7625 1450);
DISPLAY 0.489362 (-7625 1450);
PAINT SKYBLUE (-7625 1450);
DISPLAY INVISIBLE (-7625 1450);
FORCEADD UNIVERSAL_GND..1
(-2475 6275);
FORCEPROP 3 LASTPIN (-2475 6325) SIG_NAME GND\g
J 0
(-2465 6335);
DISPLAY 0.659574 (-2465 6335);
PAINT MONO (-2465 6335);
DISPLAY INVISIBLE (-2465 6335);
FORCEPROP 2 LAST CDS_LIB pure_quanta_power
J 0
(-2475 6275);
DISPLAY INVISIBLE (-2475 6275);
FORCEPROP 1 LAST HDL_POWER GND
J 1
(-2450 6200);
DISPLAY 0.872340 (-2450 6200);
PAINT GREEN (-2450 6200);
DISPLAY INVISIBLE (-2450 6200);
FORCEPROP 1 LAST PATH I130
J 0
(-2400 6275);
DISPLAY 0.872340 (-2400 6275);
PAINT AQUA (-2400 6275);
DISPLAY INVISIBLE (-2400 6275);
FORCEADD Q_CAP..1
(-2475 6525);
FORCEPROP 1 LAST LOCATION PC471
J 0
(-2425 6625);
DISPLAY 0.489362 (-2425 6625);
PAINT SKYBLUE (-2425 6625);
FORCEPROP 0 LAST $SEC 1
J 0
(-2425 6650);
DISPLAY 0.680851 (-2425 6650);
PAINT MONO (-2425 6650);
DISPLAY INVISIBLE (-2425 6650);
FORCEPROP 0 LAST CDS_SEC 1
J 0
(-2425 6650);
DISPLAY 1.021277 (-2425 6650);
DISPLAY INVISIBLE (-2425 6650);
FORCEPROP 1 LASTPIN (-2475 6625) $PN 1
J 0
(-2465 6605);
DISPLAY 0.489362 (-2465 6605);
PAINT MONO (-2465 6605);
FORCEPROP 1 LASTPIN (-2475 6425) $PN 2
J 0
(-2465 6405);
DISPLAY 0.489362 (-2465 6405);
PAINT MONO (-2465 6405);
FORCEPROP 1 LAST MATERIAL X6S
J 0
(-2425 6425);
DISPLAY 0.489362 (-2425 6425);
PAINT SKYBLUE (-2425 6425);
FORCEPROP 1 LAST VOLTAGE 16V
J 0
(-2425 6525);
DISPLAY 0.489362 (-2425 6525);
PAINT SKYBLUE (-2425 6525);
FORCEPROP 1 LAST PACK_TYPE C0402
J 0
(-2425 6325);
DISPLAY 0.489362 (-2425 6325);
PAINT SKYBLUE (-2425 6325);
FORCEPROP 1 LAST TOLERANCE 10%
J 0
(-2425 6475);
DISPLAY 0.489362 (-2425 6475);
PAINT SKYBLUE (-2425 6475);
FORCEPROP 1 LAST VALUE 1UF
J 0
(-2425 6575);
DISPLAY 0.489362 (-2425 6575);
PAINT SKYBLUE (-2425 6575);
FORCEPROP 2 LAST CDS_LIB pure_quanta
J 0
(-2475 6525);
DISPLAY INVISIBLE (-2475 6525);
FORCEPROP 1 LAST PATH I131
J 0
(-2425 6675);
DISPLAY 0.978723 (-2425 6675);
PAINT WHITE (-2425 6675);
DISPLAY INVISIBLE (-2425 6675);
FORCEPROP 1 LAST PART_NUMBER CH5103KEB01
J 0
(-2425 6375);
DISPLAY 0.489362 (-2425 6375);
PAINT SKYBLUE (-2425 6375);
DISPLAY INVISIBLE (-2425 6375);
FORCEADD OFFPAGE..5
R 2
(-2050 6200);
FORCEPROP 2 LAST $XR4 199 
J 0
(-1381 6200);
DISPLAY 0.638298 (-1381 6200);
PAINT MONO (-1381 6200);
FORCEPROP 2 LAST $XR3 198 
J 0
(-1501 6200);
DISPLAY 0.638298 (-1501 6200);
PAINT MONO (-1501 6200);
FORCEPROP 2 LAST $XR2 196 
J 0
(-1621 6200);
DISPLAY 0.638298 (-1621 6200);
PAINT MONO (-1621 6200);
FORCEPROP 2 LAST $XR1 195 
J 0
(-1741 6200);
DISPLAY 0.638298 (-1741 6200);
PAINT MONO (-1741 6200);
FORCEPROP 2 LAST $XR0 194 
J 0
(-1861 6200);
DISPLAY 0.638298 (-1861 6200);
PAINT MONO (-1861 6200);
FORCEPROP 2 LAST CDS_LIB standard
J 2
(-2050 6200);
DISPLAY INVISIBLE (-2050 6200);
FORCEPROP 1 LAST OFFPAGE TRUE
J 2
(-2375 6075);
DISPLAY 0.872340 (-2375 6075);
PAINT GREEN (-2375 6075);
DISPLAY INVISIBLE (-2375 6075);
FORCEPROP 1 LAST COMMENT_BODY TRUE
J 2
(-2150 6125);
DISPLAY 0.872340 (-2150 6125);
PAINT GREEN (-2150 6125);
DISPLAY INVISIBLE (-2150 6125);
FORCEPROP 2 LAST PATH I132
J 0
(-1375 6250);
DISPLAY 0.680851 (-1375 6250);
DISPLAY INVISIBLE (-1375 6250);
FORCEADD Q_RES..1
(-2050 6675);
FORCEPROP 1 LAST LOCATION PR316
J 0
(-2100 6725);
DISPLAY 0.489362 (-2100 6725);
PAINT SKYBLUE (-2100 6725);
FORCEPROP 0 LAST $SEC 1
J 0
(-2100 6775);
DISPLAY 0.680851 (-2100 6775);
PAINT MONO (-2100 6775);
DISPLAY INVISIBLE (-2100 6775);
FORCEPROP 0 LAST CDS_SEC 1
J 0
(-2100 6775);
DISPLAY 1.021277 (-2100 6775);
DISPLAY INVISIBLE (-2100 6775);
FORCEPROP 1 LASTPIN (-2150 6675) $PN 1
J 0
(-2138 6687);
DISPLAY 0.489362 (-2138 6687);
PAINT MONO (-2138 6687);
FORCEPROP 1 LASTPIN (-1950 6675) $PN 2
J 0
(-1988 6687);
DISPLAY 0.489362 (-1988 6687);
PAINT MONO (-1988 6687);
FORCEPROP 1 LAST VALUE 1
J 2
(-2200 6700);
DISPLAY 0.489362 (-2200 6700);
PAINT SKYBLUE (-2200 6700);
FORCEPROP 1 LAST TOLERANCE 1%
J 0
(-1925 6700);
DISPLAY 0.489362 (-1925 6700);
PAINT SKYBLUE (-1925 6700);
FORCEPROP 1 LAST MATERIAL CHIP
J 0
(-1925 6625);
DISPLAY 0.489362 (-1925 6625);
PAINT SKYBLUE (-1925 6625);
FORCEPROP 1 LAST PACK_TYPE 0402LF
J 0
(-2225 6600);
DISPLAY 0.489362 (-2225 6600);
PAINT SKYBLUE (-2225 6600);
FORCEPROP 1 LAST WATTAGE 1/16W
J 0
(-1925 6600);
DISPLAY 0.489362 (-1925 6600);
PAINT SKYBLUE (-1925 6600);
FORCEPROP 2 LAST CDS_LIB pure_quanta
J 0
(-2050 6675);
DISPLAY INVISIBLE (-2050 6675);
FORCEPROP 1 LAST PATH I133
J 0
(-2100 6825);
DISPLAY 0.978723 (-2100 6825);
PAINT WHITE (-2100 6825);
DISPLAY INVISIBLE (-2100 6825);
FORCEPROP 1 LAST PART_NUMBER CS-1002FB04
J 0
(-2225 6625);
DISPLAY 0.489362 (-2225 6625);
PAINT SKYBLUE (-2225 6625);
DISPLAY INVISIBLE (-2225 6625);
FORCEADD VCC_CORE..1
(-1625 6775);
FORCEPROP 3 LASTPIN (-1625 6725) SIG_NAME P3V3_AUX\g
J 0
(-1615 6735);
DISPLAY 0.659574 (-1615 6735);
PAINT MONO (-1615 6735);
DISPLAY INVISIBLE (-1615 6735);
FORCEPROP 1 LAST HDL_POWER P3V3_AUX
J 1
(-1625 6825);
DISPLAY 0.489362 (-1625 6825);
PAINT GREEN (-1625 6825);
FORCEPROP 2 LAST CDS_LIB pure_quanta_power
J 0
(-1625 6775);
DISPLAY INVISIBLE (-1625 6775);
FORCEPROP 1 LAST PATH I134
J 0
(-1575 6800);
DISPLAY 0.872340 (-1575 6800);
PAINT AQUA (-1575 6800);
DISPLAY INVISIBLE (-1575 6800);
FORCEADD RAA229620GNPHA0..1
(-3900 3750);
FORCEPROP 1 LAST LOCATION PU42
J 0
(-4450 6775);
DISPLAY 0.489362 (-4450 6775);
PAINT SKYBLUE (-4450 6775);
FORCEPROP 2 LAST SEC 1
J 0
(-4450 6950);
DISPLAY 0.680851 (-4450 6950);
PAINT MONO (-4450 6950);
DISPLAY INVISIBLE (-4450 6950);
FORCEPROP 2 LASTPIN (-3250 2100) $PN 38
J 0
(-3240 2110);
DISPLAY 0.489362 (-3240 2110);
PAINT MONO (-3240 2110);
FORCEPROP 2 LASTPIN (-3250 2400) $PN 37
J 0
(-3240 2410);
DISPLAY 0.489362 (-3240 2410);
PAINT MONO (-3240 2410);
FORCEPROP 2 LASTPIN (-3250 2700) $PN 36
J 0
(-3240 2710);
DISPLAY 0.489362 (-3240 2710);
PAINT MONO (-3240 2710);
FORCEPROP 2 LASTPIN (-3250 3000) $PN 35
J 0
(-3240 3010);
DISPLAY 0.489362 (-3240 3010);
PAINT MONO (-3240 3010);
FORCEPROP 2 LASTPIN (-3250 3300) $PN 34
J 0
(-3240 3310);
DISPLAY 0.489362 (-3240 3310);
PAINT MONO (-3240 3310);
FORCEPROP 2 LASTPIN (-3250 3600) $PN 33
J 0
(-3240 3610);
DISPLAY 0.489362 (-3240 3610);
PAINT MONO (-3240 3610);
FORCEPROP 2 LASTPIN (-3250 3900) $PN 32
J 0
(-3240 3910);
DISPLAY 0.489362 (-3240 3910);
PAINT MONO (-3240 3910);
FORCEPROP 2 LASTPIN (-3250 4200) $PN 31
J 0
(-3240 4210);
DISPLAY 0.489362 (-3240 4210);
PAINT MONO (-3240 4210);
FORCEPROP 2 LASTPIN (-3250 4500) $PN 30
J 0
(-3240 4510);
DISPLAY 0.489362 (-3240 4510);
PAINT MONO (-3240 4510);
FORCEPROP 2 LASTPIN (-3250 4800) $PN 29
J 0
(-3240 4810);
DISPLAY 0.489362 (-3240 4810);
PAINT MONO (-3240 4810);
FORCEPROP 2 LASTPIN (-3250 5100) $PN 28
J 0
(-3240 5110);
DISPLAY 0.489362 (-3240 5110);
PAINT MONO (-3240 5110);
FORCEPROP 2 LASTPIN (-3250 5400) $PN 27
J 0
(-3240 5410);
DISPLAY 0.489362 (-3240 5410);
PAINT MONO (-3240 5410);
FORCEPROP 2 LASTPIN (-4600 6350) $PN 17
J 2
(-4610 6360);
DISPLAY 0.489362 (-4610 6360);
PAINT MONO (-4610 6360);
FORCEPROP 2 LASTPIN (-4600 1750) $PN 42
J 2
(-4610 1760);
DISPLAY 0.489362 (-4610 1760);
PAINT MONO (-4610 1760);
FORCEPROP 2 LASTPIN (-4600 5050) $PN 15
J 2
(-4610 5060);
DISPLAY 0.489362 (-4610 5060);
PAINT MONO (-4610 5060);
FORCEPROP 2 LASTPIN (-4600 2500) $PN 41
J 2
(-4610 2510);
DISPLAY 0.489362 (-4610 2510);
PAINT MONO (-4610 2510);
FORCEPROP 2 LASTPIN (-4600 6500) $PN 16
J 2
(-4610 6510);
DISPLAY 0.489362 (-4610 6510);
PAINT MONO (-4610 6510);
FORCEPROP 2 LASTPIN (-4600 1250) $PN 20
J 2
(-4610 1260);
DISPLAY 0.489362 (-4610 1260);
PAINT MONO (-4610 1260);
FORCEPROP 2 LASTPIN (-4600 5350) $PN 14
J 2
(-4610 5360);
DISPLAY 0.489362 (-4610 5360);
PAINT MONO (-4610 5360);
FORCEPROP 2 LASTPIN (-4600 5200) $PN 13
J 2
(-4610 5210);
DISPLAY 0.489362 (-4610 5210);
PAINT MONO (-4610 5210);
FORCEPROP 2 LASTPIN (-3250 2200) $PN 1
J 0
(-3240 2210);
DISPLAY 0.489362 (-3240 2210);
PAINT MONO (-3240 2210);
FORCEPROP 2 LASTPIN (-3250 2500) $PN 2
J 0
(-3240 2510);
DISPLAY 0.489362 (-3240 2510);
PAINT MONO (-3240 2510);
FORCEPROP 2 LASTPIN (-3250 2800) $PN 3
J 0
(-3240 2810);
DISPLAY 0.489362 (-3240 2810);
PAINT MONO (-3240 2810);
FORCEPROP 2 LASTPIN (-3250 3100) $PN 4
J 0
(-3240 3110);
DISPLAY 0.489362 (-3240 3110);
PAINT MONO (-3240 3110);
FORCEPROP 2 LASTPIN (-3250 3400) $PN 5
J 0
(-3240 3410);
DISPLAY 0.489362 (-3240 3410);
PAINT MONO (-3240 3410);
FORCEPROP 2 LASTPIN (-3250 3700) $PN 6
J 0
(-3240 3710);
DISPLAY 0.489362 (-3240 3710);
PAINT MONO (-3240 3710);
FORCEPROP 2 LASTPIN (-3250 4000) $PN 7
J 0
(-3240 4010);
DISPLAY 0.489362 (-3240 4010);
PAINT MONO (-3240 4010);
FORCEPROP 2 LASTPIN (-3250 4300) $PN 8
J 0
(-3240 4310);
DISPLAY 0.489362 (-3240 4310);
PAINT MONO (-3240 4310);
FORCEPROP 2 LASTPIN (-3250 4600) $PN 9
J 0
(-3240 4610);
DISPLAY 0.489362 (-3240 4610);
PAINT MONO (-3240 4610);
FORCEPROP 2 LASTPIN (-3250 4900) $PN 10
J 0
(-3240 4910);
DISPLAY 0.489362 (-3240 4910);
PAINT MONO (-3240 4910);
FORCEPROP 2 LASTPIN (-3250 5200) $PN 11
J 0
(-3240 5210);
DISPLAY 0.489362 (-3240 5210);
PAINT MONO (-3240 5210);
FORCEPROP 2 LASTPIN (-3250 5500) $PN 12
J 0
(-3240 5510);
DISPLAY 0.489362 (-3240 5510);
PAINT MONO (-3240 5510);
FORCEPROP 2 LASTPIN (-4600 2650) $PN 18
J 2
(-4610 2660);
DISPLAY 0.489362 (-4610 2660);
PAINT MONO (-4610 2660);
FORCEPROP 2 LASTPIN (-4600 4200) $PN 26
J 2
(-4610 4210);
DISPLAY 0.489362 (-4610 4210);
PAINT MONO (-4610 4210);
FORCEPROP 2 LASTPIN (-4600 3100) $PN 39
J 2
(-4610 3110);
DISPLAY 0.489362 (-4610 3110);
PAINT MONO (-4610 3110);
FORCEPROP 2 LASTPIN (-4600 6050) $PN 22
J 2
(-4610 6060);
DISPLAY 0.489362 (-4610 6060);
PAINT MONO (-4610 6060);
FORCEPROP 2 LASTPIN (-4600 5900) $PN 21
J 2
(-4610 5910);
DISPLAY 0.489362 (-4610 5910);
PAINT MONO (-4610 5910);
FORCEPROP 2 LASTPIN (-4600 5600) $PN 24
J 2
(-4610 5610);
DISPLAY 0.489362 (-4610 5610);
PAINT MONO (-4610 5610);
FORCEPROP 2 LASTPIN (-4600 5750) $PN 23
J 2
(-4610 5760);
DISPLAY 0.489362 (-4610 5760);
PAINT MONO (-4610 5760);
FORCEPROP 2 LASTPIN (-3250 1300) $PN 44
J 0
(-3240 1310);
DISPLAY 0.489362 (-3240 1310);
PAINT MONO (-3240 1310);
FORCEPROP 2 LASTPIN (-3250 1600) $PN 43
J 0
(-3240 1610);
DISPLAY 0.489362 (-3240 1610);
PAINT MONO (-3240 1610);
FORCEPROP 2 LASTPIN (-4600 950) $PN TH
J 2
(-4610 960);
DISPLAY 0.489362 (-4610 960);
PAINT MONO (-4610 960);
FORCEPROP 2 LASTPIN (-3250 6500) $PN 47
J 0
(-3240 6510);
DISPLAY 0.489362 (-3240 6510);
PAINT MONO (-3240 6510);
FORCEPROP 2 LASTPIN (-3250 6200) $PN 48
J 0
(-3240 6210);
DISPLAY 0.489362 (-3240 6210);
PAINT MONO (-3240 6210);
FORCEPROP 2 LASTPIN (-4600 2250) $PN 19
J 2
(-4610 2260);
DISPLAY 0.489362 (-4610 2260);
PAINT MONO (-4610 2260);
FORCEPROP 2 LASTPIN (-4600 1050) $PN 46
J 2
(-4610 1060);
DISPLAY 0.489362 (-4610 1060);
PAINT MONO (-4610 1060);
FORCEPROP 2 LASTPIN (-4600 1150) $PN 45
J 2
(-4610 1160);
DISPLAY 0.489362 (-4610 1160);
PAINT MONO (-4610 1160);
FORCEPROP 2 LASTPIN (-4600 4450) $PN 25
J 2
(-4610 4460);
DISPLAY 0.489362 (-4610 4460);
PAINT MONO (-4610 4460);
FORCEPROP 2 LASTPIN (-4600 3350) $PN 40
J 2
(-4610 3360);
DISPLAY 0.489362 (-4610 3360);
PAINT MONO (-4610 3360);
FORCEPROP 2 LAST PART_TYPE SMLF
J 0
(-4450 6900);
DISPLAY 1.021277 (-4450 6900);
FORCEPROP 1 LAST MATERIAL IC
J 0
(-4450 6625);
DISPLAY 0.489362 (-4450 6625);
PAINT SKYBLUE (-4450 6625);
FORCEPROP 2 LAST VALUE RAA229620GNP#HA0
J 0
(-4450 6850);
DISPLAY 0.489362 (-4450 6850);
PAINT SKYBLUE (-4450 6850);
FORCEPROP 1 LAST CDS_LMAN_SYM_OUTLINE -550,2850,500,-2850
J 0
(-3900 3750);
DISPLAY 0.468085 (-3900 3750);
PAINT GREEN (-3900 3750);
DISPLAY INVISIBLE (-3900 3750);
FORCEPROP 1 LAST NEEDS_NO_SIZE TRUE
J 0
(-3900 3750);
DISPLAY 0.723404 (-3900 3750);
PAINT GREEN (-3900 3750);
DISPLAY INVISIBLE (-3900 3750);
FORCEPROP 2 LAST CDS_LIB pure_quanta
J 0
(-3900 3750);
DISPLAY INVISIBLE (-3900 3750);
FORCEPROP 2 LAST SEC_TYPE 
J 0
(-4450 6950);
DISPLAY 1.021277 (-4450 6950);
DISPLAY INVISIBLE (-4450 6950);
FORCEPROP 1 LAST PATH I135
J 0
(-3900 3750);
DISPLAY 0.723404 (-3900 3750);
PAINT GREEN (-3900 3750);
DISPLAY INVISIBLE (-3900 3750);
FORCEPROP 1 LAST PART_NUMBER ARF0TGP4002
J 0
(-4450 6700);
DISPLAY 0.489362 (-4450 6700);
PAINT SKYBLUE (-4450 6700);
DISPLAY INVISIBLE (-4450 6700);
FORCEADD Q_RES..2
(-7950 1575);
FORCEPROP 1 LAST LOCATION R6089
J 0
(-8200 1675);
DISPLAY 0.404255 (-8200 1675);
FORCEPROP 0 LAST $SEC 1
J 0
(-8200 1700);
DISPLAY 0.680851 (-8200 1700);
PAINT MONO (-8200 1700);
DISPLAY INVISIBLE (-8200 1700);
FORCEPROP 0 LAST CDS_SEC 1
J 0
(-8200 1700);
DISPLAY 0.680851 (-8200 1700);
DISPLAY INVISIBLE (-8200 1700);
FORCEPROP 1 LASTPIN (-7950 1675) $PN 1
J 0
(-7945 1637);
DISPLAY 0.787234 (-7945 1637);
PAINT MONO (-7945 1637);
FORCEPROP 1 LASTPIN (-7950 1475) $PN 2
J 0
(-7945 1485);
DISPLAY 0.787234 (-7945 1485);
PAINT MONO (-7945 1485);
FORCEPROP 1 LAST VALUE 10K
J 0
(-8200 1625);
DISPLAY 0.404255 (-8200 1625);
FORCEPROP 1 LAST TOLERANCE 1%
J 0
(-8195 1575);
DISPLAY 0.404255 (-8195 1575);
FORCEPROP 1 LAST WATTAGE 1/16W
J 0
(-8200 1525);
DISPLAY 0.404255 (-8200 1525);
FORCEPROP 1 LAST MATERIAL EMPTY
J 0
(-8200 1475);
DISPLAY 0.404255 (-8200 1475);
FORCEPROP 1 LAST PACK_TYPE 0402LF
J 0
(-8200 1375);
DISPLAY 0.404255 (-8200 1375);
FORCEPROP 2 LAST CDS_LIB pure_quanta
J 0
(-7950 1575);
DISPLAY INVISIBLE (-7950 1575);
FORCEPROP 1 LAST PATH I136
J 0
(-7900 1750);
DISPLAY 0.978723 (-7900 1750);
PAINT WHITE (-7900 1750);
DISPLAY INVISIBLE (-7900 1750);
FORCEPROP 1 LAST PART_NUMBER CS31002FB08
J 0
(-8200 1425);
DISPLAY 0.404255 (-8200 1425);
DISPLAY INVISIBLE (-8200 1425);
FORCEADD UNIVERSAL_GND..1
R 7
(-7050 1525);
FORCEPROP 3 LASTPIN (-7000 1525) SIG_NAME GND\g
J 0
(-6990 1535);
DISPLAY 0.659574 (-6990 1535);
PAINT MONO (-6990 1535);
DISPLAY INVISIBLE (-6990 1535);
FORCEPROP 2 LAST CDS_LIB pure_quanta_power
R 1
J 0
(-7050 1525);
DISPLAY INVISIBLE (-7050 1525);
FORCEPROP 1 LAST HDL_POWER GND
R 1
J 1
(-7125 1550);
DISPLAY 0.872340 (-7125 1550);
PAINT GREEN (-7125 1550);
DISPLAY INVISIBLE (-7125 1550);
FORCEPROP 1 LAST PATH I137
R 1
J 0
(-7050 1600);
DISPLAY 0.872340 (-7050 1600);
PAINT AQUA (-7050 1600);
DISPLAY INVISIBLE (-7050 1600);
FORCEADD Q_CAP..2
(-6750 1525);
FORCEPROP 1 LAST LOCATION C5018
J 1
(-6925 1525);
DISPLAY 0.489362 (-6925 1525);
PAINT SKYBLUE (-6925 1525);
FORCEPROP 0 LAST $SEC 1
J 0
(-6800 1625);
DISPLAY 0.680851 (-6800 1625);
PAINT MONO (-6800 1625);
DISPLAY INVISIBLE (-6800 1625);
FORCEPROP 0 LAST CDS_SEC 1
J 0
(-6800 1625);
DISPLAY 1.021277 (-6800 1625);
DISPLAY INVISIBLE (-6800 1625);
FORCEPROP 1 LASTPIN (-6850 1525) $PN 1
J 0
(-6860 1540);
DISPLAY 0.489362 (-6860 1540);
PAINT MONO (-6860 1540);
FORCEPROP 1 LASTPIN (-6650 1525) $PN 2
J 0
(-6665 1540);
DISPLAY 0.489362 (-6665 1540);
PAINT MONO (-6665 1540);
FORCEPROP 1 LAST MATERIAL X7R
J 0
(-7000 1575);
DISPLAY 0.489362 (-7000 1575);
PAINT SKYBLUE (-7000 1575);
FORCEPROP 1 LAST TOLERANCE 5%
J 2
(-7025 1575);
DISPLAY 0.489362 (-7025 1575);
PAINT SKYBLUE (-7025 1575);
FORCEPROP 1 LAST VOLTAGE 50V
J 0
(-7175 1575);
DISPLAY 0.489362 (-7175 1575);
PAINT SKYBLUE (-7175 1575);
FORCEPROP 1 LAST PACK_TYPE 0402
J 1
(-6850 1575);
DISPLAY 0.489362 (-6850 1575);
PAINT SKYBLUE (-6850 1575);
FORCEPROP 1 LAST VALUE 1000PF
J 2
(-6475 1525);
DISPLAY 0.489362 (-6475 1525);
PAINT SKYBLUE (-6475 1525);
FORCEPROP 2 LAST CDS_LIB pure_quanta
J 0
(-6750 1525);
DISPLAY INVISIBLE (-6750 1525);
FORCEPROP 1 LAST PATH I138
J 0
(-6750 1725);
DISPLAY 0.978723 (-6750 1725);
PAINT WHITE (-6750 1725);
DISPLAY INVISIBLE (-6750 1725);
FORCEPROP 1 LAST PART_NUMBER TMP_QCH21006JB10
J 1
(-7000 1600);
DISPLAY 0.489362 (-7000 1600);
PAINT SKYBLUE (-7000 1600);
DISPLAY INVISIBLE (-7000 1600);
FORCEADD Q_CAP..2
(-6450 6625);
FORCEPROP 1 LAST LOCATION C5017
J 1
(-6625 6625);
DISPLAY 0.489362 (-6625 6625);
PAINT SKYBLUE (-6625 6625);
FORCEPROP 0 LAST $SEC 1
J 0
(-6500 6725);
DISPLAY 0.680851 (-6500 6725);
PAINT MONO (-6500 6725);
DISPLAY INVISIBLE (-6500 6725);
FORCEPROP 0 LAST CDS_SEC 1
J 0
(-6500 6725);
DISPLAY 1.021277 (-6500 6725);
DISPLAY INVISIBLE (-6500 6725);
FORCEPROP 1 LASTPIN (-6550 6625) $PN 1
J 0
(-6560 6640);
DISPLAY 0.489362 (-6560 6640);
PAINT MONO (-6560 6640);
FORCEPROP 1 LASTPIN (-6350 6625) $PN 2
J 0
(-6365 6640);
DISPLAY 0.489362 (-6365 6640);
PAINT MONO (-6365 6640);
FORCEPROP 1 LAST PACK_TYPE 0402
J 1
(-6550 6675);
DISPLAY 0.489362 (-6550 6675);
PAINT SKYBLUE (-6550 6675);
FORCEPROP 1 LAST VOLTAGE 50V
J 0
(-6875 6675);
DISPLAY 0.489362 (-6875 6675);
PAINT SKYBLUE (-6875 6675);
FORCEPROP 1 LAST MATERIAL X7R
J 0
(-6700 6675);
DISPLAY 0.489362 (-6700 6675);
PAINT SKYBLUE (-6700 6675);
FORCEPROP 1 LAST VALUE 1000PF
J 2
(-6175 6625);
DISPLAY 0.489362 (-6175 6625);
PAINT SKYBLUE (-6175 6625);
FORCEPROP 1 LAST TOLERANCE 5%
J 2
(-6725 6675);
DISPLAY 0.489362 (-6725 6675);
PAINT SKYBLUE (-6725 6675);
FORCEPROP 2 LAST CDS_LIB pure_quanta
J 0
(-6450 6625);
DISPLAY INVISIBLE (-6450 6625);
FORCEPROP 1 LAST PATH I139
J 0
(-6450 6825);
DISPLAY 0.978723 (-6450 6825);
PAINT WHITE (-6450 6825);
DISPLAY INVISIBLE (-6450 6825);
FORCEPROP 1 LAST PART_NUMBER TMP_QCH21006JB10
J 1
(-6700 6700);
DISPLAY 0.489362 (-6700 6700);
PAINT SKYBLUE (-6700 6700);
DISPLAY INVISIBLE (-6700 6700);
FORCEADD VCC_CORE..1
(-7125 1350);
FORCEPROP 3 LASTPIN (-7125 1300) SIG_NAME P5V_AUX\g
J 0
(-7115 1310);
DISPLAY 0.659574 (-7115 1310);
PAINT MONO (-7115 1310);
DISPLAY INVISIBLE (-7115 1310);
FORCEPROP 1 LAST HDL_POWER P5V_AUX
J 1
(-7125 1400);
DISPLAY 0.489362 (-7125 1400);
PAINT GREEN (-7125 1400);
FORCEPROP 2 LAST CDS_LIB pure_quanta_power
J 0
(-7125 1350);
DISPLAY INVISIBLE (-7125 1350);
FORCEPROP 1 LAST PATH I14
J 0
(-7075 1375);
DISPLAY 0.872340 (-7075 1375);
PAINT AQUA (-7075 1375);
DISPLAY INVISIBLE (-7075 1375);
FORCEADD UNIVERSAL_GND..1
R 7
(-6750 6625);
FORCEPROP 3 LASTPIN (-6700 6625) SIG_NAME GND\g
J 0
(-6690 6635);
DISPLAY 0.659574 (-6690 6635);
PAINT MONO (-6690 6635);
DISPLAY INVISIBLE (-6690 6635);
FORCEPROP 2 LAST CDS_LIB pure_quanta_power
R 1
J 0
(-6750 6625);
DISPLAY INVISIBLE (-6750 6625);
FORCEPROP 1 LAST HDL_POWER GND
R 1
J 1
(-6825 6650);
DISPLAY 0.872340 (-6825 6650);
PAINT GREEN (-6825 6650);
DISPLAY INVISIBLE (-6825 6650);
FORCEPROP 1 LAST PATH I140
R 1
J 0
(-6750 6700);
DISPLAY 0.872340 (-6750 6700);
PAINT AQUA (-6750 6700);
DISPLAY INVISIBLE (-6750 6700);
FORCEADD UNIVERSAL_GND..1
(-5225 4575);
FORCEPROP 3 LASTPIN (-5225 4625) SIG_NAME GND\g
J 0
(-5215 4635);
DISPLAY 0.659574 (-5215 4635);
PAINT MONO (-5215 4635);
DISPLAY INVISIBLE (-5215 4635);
FORCEPROP 2 LAST CDS_LIB pure_quanta_power
J 0
(-5225 4575);
PAINT MONO (-5225 4575);
DISPLAY INVISIBLE (-5225 4575);
FORCEPROP 1 LAST HDL_POWER GND
J 1
(-5200 4500);
DISPLAY 0.872340 (-5200 4500);
PAINT GREEN (-5200 4500);
DISPLAY INVISIBLE (-5200 4500);
FORCEPROP 1 LAST PATH I141
J 0
(-5150 4575);
DISPLAY 0.872340 (-5150 4575);
PAINT AQUA (-5150 4575);
DISPLAY INVISIBLE (-5150 4575);
FORCEADD Q_CAP..1
(-5225 4775);
FORCEPROP 1 LAST LOCATION C5011
J 0
(-5125 4775);
DISPLAY 0.510638 (-5125 4775);
FORCEPROP 0 LAST $SEC 1
J 0
(-4975 4800);
DISPLAY 0.680851 (-4975 4800);
PAINT MONO (-4975 4800);
DISPLAY INVISIBLE (-4975 4800);
FORCEPROP 0 LAST CDS_SEC 1
J 0
(-4975 4800);
DISPLAY 0.680851 (-4975 4800);
DISPLAY INVISIBLE (-4975 4800);
FORCEPROP 1 LASTPIN (-5225 4875) $PN 1
J 0
(-5215 4855);
DISPLAY 0.787234 (-5215 4855);
PAINT MONO (-5215 4855);
FORCEPROP 1 LASTPIN (-5225 4675) $PN 2
J 0
(-5215 4655);
DISPLAY 0.787234 (-5215 4655);
PAINT MONO (-5215 4655);
FORCEPROP 1 LAST TOLERANCE 5%
J 0
(-4975 4675);
DISPLAY 0.510638 (-4975 4675);
FORCEPROP 1 LAST PACK_TYPE 0402
J 0
(-4975 4750);
DISPLAY 0.510638 (-4975 4750);
FORCEPROP 1 LAST VOLTAGE 50V
J 0
(-4975 4700);
DISPLAY 0.510638 (-4975 4700);
FORCEPROP 1 LAST MATERIAL X7R
J 0
(-4975 4725);
DISPLAY 0.510638 (-4975 4725);
FORCEPROP 1 LAST VALUE 1000PF
J 0
(-5150 4750);
DISPLAY 0.510638 (-5150 4750);
FORCEPROP 2 LAST CDS_LIB pure_quanta
J 0
(-5225 4775);
DISPLAY INVISIBLE (-5225 4775);
FORCEPROP 1 LAST PATH I142
J 0
(-5175 4925);
DISPLAY 0.978723 (-5175 4925);
PAINT WHITE (-5175 4925);
DISPLAY INVISIBLE (-5175 4925);
FORCEPROP 1 LAST PART_NUMBER TMP_QCH21006JB10
J 0
(-4975 4775);
DISPLAY 0.510638 (-4975 4775);
DISPLAY INVISIBLE (-4975 4775);
FORCEADD CONN3_210HP1030BR1..1
R 2
(-6150 4675);
FORCEPROP 1 LAST LOCATION PJ1
J 2
(-6100 4850);
DISPLAY 0.723404 (-6100 4850);
PAINT GREEN (-6100 4850);
FORCEPROP 0 LAST $SEC 1
J 0
(-6050 5000);
DISPLAY 0.680851 (-6050 5000);
PAINT MONO (-6050 5000);
DISPLAY INVISIBLE (-6050 5000);
FORCEPROP 0 LAST CDS_SEC 1
J 0
(-6050 5000);
DISPLAY 0.680851 (-6050 5000);
DISPLAY INVISIBLE (-6050 5000);
FORCEPROP 0 LASTPIN (-5950 4725) $PN 1
J 0
(-5940 4735);
DISPLAY 0.680851 (-5940 4735);
PAINT MONO (-5940 4735);
FORCEPROP 0 LASTPIN (-5950 4675) $PN 2
J 0
(-5940 4685);
DISPLAY 0.680851 (-5940 4685);
PAINT MONO (-5940 4685);
FORCEPROP 0 LASTPIN (-5950 4625) $PN 3
J 0
(-5940 4635);
DISPLAY 0.680851 (-5940 4635);
PAINT MONO (-5940 4635);
FORCEPROP 1 LAST MATERIAL IO
J 2
(-6125 4775);
DISPLAY 0.723404 (-6125 4775);
PAINT GREEN (-6125 4775);
FORCEPROP 2 LAST PART_TYPE THLF
J 2
(-6050 4950);
DISPLAY 0.680851 (-6050 4950);
FORCEPROP 2 LAST VALUE CONN3_210-HP1-030BR1
J 2
(-5675 4900);
DISPLAY 0.553191 (-5675 4900);
FORCEPROP 2 LAST CDS_LIB pure_quanta
J 2
(-6150 4769);
DISPLAY INVISIBLE (-6150 4769);
FORCEPROP 1 LAST NEEDS_NO_SIZE TRUE
J 2
(-6150 4743);
DISPLAY 0.723404 (-6150 4743);
PAINT GREEN (-6150 4743);
DISPLAY INVISIBLE (-6150 4743);
FORCEPROP 1 LAST CDS_LMAN_SYM_OUTLINE -50,100,50,-100
J 2
(-6150 4719);
DISPLAY 0.468085 (-6150 4719);
PAINT GREEN (-6150 4719);
DISPLAY INVISIBLE (-6150 4719);
FORCEPROP 1 LAST PATH I143
J 2
(-6150 4743);
DISPLAY 0.723404 (-6150 4743);
PAINT GREEN (-6150 4743);
DISPLAY INVISIBLE (-6150 4743);
FORCEPROP 1 LAST PART_NUMBER DFHD03MS213
J 2
(-5875 4825);
DISPLAY 0.574468 (-5875 4825);
PAINT GREEN (-5875 4825);
DISPLAY INVISIBLE (-5875 4825);
FORCEADD OFFPAGE..3
(-5500 4675);
FORCEPROP 2 LAST $XR1 193 
J 0
(-5166 4639);
DISPLAY 0.638298 (-5166 4639);
PAINT MONO (-5166 4639);
FORCEPROP 2 LAST $XR0 151 
J 0
(-5166 4675);
DISPLAY 0.638298 (-5166 4675);
PAINT MONO (-5166 4675);
FORCEPROP 2 LAST CDS_LIB standard
J 2
(-5500 4675);
DISPLAY INVISIBLE (-5500 4675);
FORCEPROP 1 LAST OFFPAGE TRUE
J 0
(-5175 4550);
DISPLAY 0.872340 (-5175 4550);
PAINT GREEN (-5175 4550);
DISPLAY INVISIBLE (-5175 4550);
FORCEPROP 1 LAST COMMENT_BODY TRUE
J 0
(-5550 4575);
DISPLAY 0.872340 (-5550 4575);
PAINT GREEN (-5550 4575);
DISPLAY INVISIBLE (-5550 4575);
FORCEPROP 2 LAST PATH I144
J 2
(-5550 4750);
DISPLAY 0.680851 (-5550 4750);
DISPLAY INVISIBLE (-5550 4750);
FORCEADD UNIVERSAL_GND..1
R 3
(-5375 4725);
FORCEPROP 3 LASTPIN (-5425 4725) SIG_NAME GND\g
J 0
(-5415 4735);
DISPLAY 0.659574 (-5415 4735);
PAINT MONO (-5415 4735);
DISPLAY INVISIBLE (-5415 4735);
FORCEPROP 2 LAST CDS_LIB pure_quanta_power
R 1
J 2
(-5375 4725);
DISPLAY INVISIBLE (-5375 4725);
FORCEPROP 1 LAST HDL_POWER GND
R 1
J 1
(-5300 4700);
DISPLAY 0.872340 (-5300 4700);
PAINT GREEN (-5300 4700);
DISPLAY INVISIBLE (-5300 4700);
FORCEPROP 1 LAST PATH I145
R 1
J 2
(-5375 4650);
DISPLAY 0.872340 (-5375 4650);
PAINT AQUA (-5375 4650);
DISPLAY INVISIBLE (-5375 4650);
FORCEADD OFFPAGE..4
(-5500 4625);
FORCEPROP 2 LAST $XR1 193 
J 0
(-4954 4625);
DISPLAY 0.638298 (-4954 4625);
PAINT MONO (-4954 4625);
FORCEPROP 2 LAST $XR0 151 
J 0
(-5074 4625);
DISPLAY 0.638298 (-5074 4625);
PAINT MONO (-5074 4625);
FORCEPROP 2 LAST CDS_LIB standard
J 2
(-5500 4625);
DISPLAY INVISIBLE (-5500 4625);
FORCEPROP 1 LAST OFFPAGE TRUE
J 0
(-5175 4500);
DISPLAY 0.872340 (-5175 4500);
PAINT GREEN (-5175 4500);
DISPLAY INVISIBLE (-5175 4500);
FORCEPROP 1 LAST COMMENT_BODY TRUE
J 0
(-5525 4525);
DISPLAY 0.872340 (-5525 4525);
PAINT GREEN (-5525 4525);
DISPLAY INVISIBLE (-5525 4525);
FORCEPROP 2 LAST PATH I146
J 2
(-5550 4700);
DISPLAY 0.680851 (-5550 4700);
DISPLAY INVISIBLE (-5550 4700);
FORCEADD Q_RES..1
(-5625 6050);
FORCEPROP 1 LAST LOCATION PR8005
J 0
(-5675 6100);
DISPLAY 0.489362 (-5675 6100);
PAINT SKYBLUE (-5675 6100);
FORCEPROP 0 LAST $SEC 1
J 0
(-5675 6125);
DISPLAY 0.680851 (-5675 6125);
PAINT MONO (-5675 6125);
DISPLAY INVISIBLE (-5675 6125);
FORCEPROP 0 LAST CDS_SEC 1
J 0
(-5675 6125);
DISPLAY 0.680851 (-5675 6125);
DISPLAY INVISIBLE (-5675 6125);
FORCEPROP 1 LASTPIN (-5725 6050) $PN 1
J 0
(-5713 6062);
DISPLAY 0.787234 (-5713 6062);
PAINT MONO (-5713 6062);
FORCEPROP 1 LASTPIN (-5525 6050) $PN 2
J 0
(-5563 6062);
DISPLAY 0.787234 (-5563 6062);
PAINT MONO (-5563 6062);
FORCEPROP 1 LAST TOLERANCE 5%
J 0
(-5500 6075);
DISPLAY 0.489362 (-5500 6075);
PAINT SKYBLUE (-5500 6075);
FORCEPROP 1 LAST PACK_TYPE 0402LF
J 0
(-5525 5975);
DISPLAY 0.489362 (-5525 5975);
PAINT SKYBLUE (-5525 5975);
FORCEPROP 1 LAST WATTAGE 1/16W
J 0
(-5525 6000);
DISPLAY 0.489362 (-5525 6000);
PAINT SKYBLUE (-5525 6000);
FORCEPROP 1 LAST VALUE 0
J 2
(-5750 6075);
DISPLAY 0.489362 (-5750 6075);
PAINT SKYBLUE (-5750 6075);
FORCEPROP 1 LAST MATERIAL CHIP
J 0
(-5875 5975);
DISPLAY 0.489362 (-5875 5975);
PAINT SKYBLUE (-5875 5975);
FORCEPROP 2 LAST CDS_LIB pure_quanta
J 0
(-5625 6050);
DISPLAY INVISIBLE (-5625 6050);
FORCEPROP 1 LAST PATH I147
J 0
(-5675 6200);
DISPLAY 0.978723 (-5675 6200);
PAINT WHITE (-5675 6200);
DISPLAY INVISIBLE (-5675 6200);
FORCEPROP 1 LAST PART_NUMBER CS00002JB13
J 0
(-5875 6000);
DISPLAY 0.489362 (-5875 6000);
PAINT SKYBLUE (-5875 6000);
DISPLAY INVISIBLE (-5875 6000);
FORCEADD Q_RES..1
(-5600 5900);
FORCEPROP 1 LAST LOCATION PR8006
J 0
(-5650 5950);
DISPLAY 0.489362 (-5650 5950);
PAINT SKYBLUE (-5650 5950);
FORCEPROP 0 LAST $SEC 1
J 0
(-5650 5975);
DISPLAY 0.680851 (-5650 5975);
PAINT MONO (-5650 5975);
DISPLAY INVISIBLE (-5650 5975);
FORCEPROP 0 LAST CDS_SEC 1
J 0
(-5650 5975);
DISPLAY 0.680851 (-5650 5975);
DISPLAY INVISIBLE (-5650 5975);
FORCEPROP 1 LASTPIN (-5700 5900) $PN 1
J 0
(-5688 5912);
DISPLAY 0.787234 (-5688 5912);
PAINT MONO (-5688 5912);
FORCEPROP 1 LASTPIN (-5500 5900) $PN 2
J 0
(-5538 5912);
DISPLAY 0.787234 (-5538 5912);
PAINT MONO (-5538 5912);
FORCEPROP 1 LAST MATERIAL CHIP
J 0
(-5850 5825);
DISPLAY 0.489362 (-5850 5825);
PAINT SKYBLUE (-5850 5825);
FORCEPROP 1 LAST WATTAGE 1/16W
J 0
(-5500 5850);
DISPLAY 0.489362 (-5500 5850);
PAINT SKYBLUE (-5500 5850);
FORCEPROP 1 LAST PACK_TYPE 0402LF
J 0
(-5500 5825);
DISPLAY 0.489362 (-5500 5825);
PAINT SKYBLUE (-5500 5825);
FORCEPROP 1 LAST TOLERANCE 5%
J 0
(-5475 5925);
DISPLAY 0.489362 (-5475 5925);
PAINT SKYBLUE (-5475 5925);
FORCEPROP 1 LAST VALUE 0
J 2
(-5725 5925);
DISPLAY 0.489362 (-5725 5925);
PAINT SKYBLUE (-5725 5925);
FORCEPROP 2 LAST CDS_LIB pure_quanta
J 0
(-5600 5900);
DISPLAY INVISIBLE (-5600 5900);
FORCEPROP 1 LAST PATH I148
J 0
(-5650 6050);
DISPLAY 0.978723 (-5650 6050);
PAINT WHITE (-5650 6050);
DISPLAY INVISIBLE (-5650 6050);
FORCEPROP 1 LAST PART_NUMBER CS00002JB13
J 0
(-5850 5850);
DISPLAY 0.489362 (-5850 5850);
PAINT SKYBLUE (-5850 5850);
DISPLAY INVISIBLE (-5850 5850);
FORCEADD Q_RES..1
(-6825 1225);
FORCEPROP 1 LAST LOCATION PR290
J 0
(-6875 1275);
DISPLAY 0.489362 (-6875 1275);
PAINT SKYBLUE (-6875 1275);
FORCEPROP 0 LAST $SEC 1
J 0
(-6875 1325);
DISPLAY 0.680851 (-6875 1325);
PAINT MONO (-6875 1325);
DISPLAY INVISIBLE (-6875 1325);
FORCEPROP 0 LAST CDS_SEC 1
J 0
(-6875 1325);
DISPLAY 1.021277 (-6875 1325);
DISPLAY INVISIBLE (-6875 1325);
FORCEPROP 1 LASTPIN (-6925 1225) $PN 1
J 0
(-6913 1237);
DISPLAY 0.489362 (-6913 1237);
PAINT MONO (-6913 1237);
FORCEPROP 1 LASTPIN (-6725 1225) $PN 2
J 0
(-6763 1237);
DISPLAY 0.489362 (-6763 1237);
PAINT MONO (-6763 1237);
FORCEPROP 1 LAST TOLERANCE 1%
J 0
(-6675 1250);
DISPLAY 0.489362 (-6675 1250);
PAINT SKYBLUE (-6675 1250);
FORCEPROP 1 LAST VALUE 40.2K
J 2
(-6975 1250);
DISPLAY 0.489362 (-6975 1250);
PAINT SKYBLUE (-6975 1250);
FORCEPROP 1 LAST WATTAGE 1/16W
J 0
(-6700 1175);
DISPLAY 0.489362 (-6700 1175);
PAINT SKYBLUE (-6700 1175);
FORCEPROP 1 LAST PACK_TYPE 0402LF
J 0
(-6700 1150);
DISPLAY 0.489362 (-6700 1150);
PAINT SKYBLUE (-6700 1150);
FORCEPROP 1 LAST MATERIAL CHIP
J 0
(-7125 1150);
DISPLAY 0.489362 (-7125 1150);
PAINT SKYBLUE (-7125 1150);
FORCEPROP 2 LAST CDS_LIB pure_quanta
J 0
(-6825 1225);
DISPLAY INVISIBLE (-6825 1225);
FORCEPROP 1 LAST PATH I15
J 0
(-6875 1375);
DISPLAY 0.978723 (-6875 1375);
PAINT WHITE (-6875 1375);
DISPLAY INVISIBLE (-6875 1375);
FORCEPROP 1 LAST PART_NUMBER CS34022FB04
J 0
(-7125 1175);
DISPLAY 0.489362 (-7125 1175);
PAINT SKYBLUE (-7125 1175);
DISPLAY INVISIBLE (-7125 1175);
FORCEADD OFFPAGE..2
R 2
(-6650 1400);
FORCEPROP 2 LAST $XR0 82 
J 0
(-6904 1400);
DISPLAY 0.638298 (-6904 1400);
PAINT MONO (-6904 1400);
FORCEPROP 2 LAST CDS_LIB standard
J 0
(-6650 1400);
DISPLAY INVISIBLE (-6650 1400);
FORCEPROP 1 LAST OFFPAGE TRUE
J 2
(-6975 1275);
DISPLAY 0.872340 (-6975 1275);
PAINT GREEN (-6975 1275);
DISPLAY INVISIBLE (-6975 1275);
FORCEPROP 1 LAST COMMENT_BODY TRUE
J 2
(-6605 1305);
DISPLAY 0.872340 (-6605 1305);
PAINT GREEN (-6605 1305);
DISPLAY INVISIBLE (-6605 1305);
FORCEPROP 2 LAST PATH I16
J 0
(-6900 1450);
DISPLAY 0.680851 (-6900 1450);
DISPLAY INVISIBLE (-6900 1450);
FORCEADD MOSFET_N..1
(-7400 1925);
FORCEPROP 1 LAST LOCATION PQ17
J 0
(-7275 1925);
DISPLAY 0.489362 (-7275 1925);
PAINT SKYBLUE (-7275 1925);
FORCEPROP 0 LAST $SEC 1
J 0
(-7275 1950);
DISPLAY 0.680851 (-7275 1950);
PAINT MONO (-7275 1950);
DISPLAY INVISIBLE (-7275 1950);
FORCEPROP 0 LAST CDS_SEC 1
J 0
(-7275 1950);
DISPLAY 1.021277 (-7275 1950);
DISPLAY INVISIBLE (-7275 1950);
FORCEPROP 1 LASTPIN (-7350 2025) $PN D
R 1
J 0
(-7350 2018);
DISPLAY 0.489362 (-7350 2018);
PAINT MONO (-7350 2018);
FORCEPROP 1 LASTPIN (-7500 1825) $PN G
J 2
(-7490 1828);
DISPLAY 0.489362 (-7490 1828);
PAINT MONO (-7490 1828);
FORCEPROP 1 LASTPIN (-7350 1725) $PN S
R 1
J 2
(-7350 1738);
DISPLAY 0.489362 (-7350 1738);
PAINT MONO (-7350 1738);
FORCEPROP 1 LAST MATERIAL IC
J 0
(-7275 1775);
DISPLAY 0.489362 (-7275 1775);
PAINT SKYBLUE (-7275 1775);
FORCEPROP 1 LAST VALUE BSS138K
J 0
(-7275 1875);
DISPLAY 0.489362 (-7275 1875);
PAINT SKYBLUE (-7275 1875);
FORCEPROP 2 LAST PATH I17
J 0
(-7275 1950);
DISPLAY 0.680851 (-7275 1950);
FORCEPROP 0 LAST MANUF_PN BSS138K
J 0
(-7300 1725);
DISPLAY 1.021277 (-7300 1725);
DISPLAY INVISIBLE (-7300 1725);
FORCEPROP 2 LAST CDS_LIB pure_quanta
J 0
(-7400 1925);
DISPLAY INVISIBLE (-7400 1925);
FORCEPROP 1 LAST CDS_LMAN_SYM_OUTLINE -50,50,100,-150
J 0
(-7400 1925);
DISPLAY 0.468085 (-7400 1925);
PAINT GREEN (-7400 1925);
DISPLAY INVISIBLE (-7400 1925);
FORCEPROP 1 LAST PACK_TYPE SMLF
J 0
(-7375 1675);
DISPLAY 0.723404 (-7375 1675);
PAINT SKYBLUE (-7375 1675);
DISPLAY INVISIBLE (-7375 1675);
FORCEPROP 1 LAST PART_NUMBER BAM138K0000
J 0
(-7275 1825);
DISPLAY 0.489362 (-7275 1825);
PAINT SKYBLUE (-7275 1825);
DISPLAY INVISIBLE (-7275 1825);
FORCEADD Q_RES..2
(-7350 2425);
FORCEPROP 1 LAST LOCATION PR285
J 0
(-7300 2475);
DISPLAY 0.489362 (-7300 2475);
PAINT SKYBLUE (-7300 2475);
FORCEPROP 0 LAST $SEC 1
J 0
(-7325 2500);
DISPLAY 0.680851 (-7325 2500);
PAINT MONO (-7325 2500);
DISPLAY INVISIBLE (-7325 2500);
FORCEPROP 0 LAST CDS_SEC 1
J 0
(-7325 2500);
DISPLAY 1.021277 (-7325 2500);
DISPLAY INVISIBLE (-7325 2500);
FORCEPROP 1 LASTPIN (-7350 2525) $PN 1
J 0
(-7345 2487);
DISPLAY 0.489362 (-7345 2487);
PAINT MONO (-7345 2487);
FORCEPROP 1 LASTPIN (-7350 2325) $PN 2
J 0
(-7345 2335);
DISPLAY 0.489362 (-7345 2335);
PAINT MONO (-7345 2335);
FORCEPROP 1 LAST PACK_TYPE 0402LF
J 0
(-7300 2325);
DISPLAY 0.489362 (-7300 2325);
PAINT SKYBLUE (-7300 2325);
FORCEPROP 1 LAST VALUE 1K
J 0
(-7300 2450);
DISPLAY 0.489362 (-7300 2450);
PAINT SKYBLUE (-7300 2450);
FORCEPROP 1 LAST TOLERANCE 1%
J 0
(-7300 2425);
DISPLAY 0.489362 (-7300 2425);
PAINT SKYBLUE (-7300 2425);
FORCEPROP 1 LAST MATERIAL CHIP
J 0
(-7300 2375);
DISPLAY 0.489362 (-7300 2375);
PAINT SKYBLUE (-7300 2375);
FORCEPROP 1 LAST WATTAGE 1/16W
J 0
(-7300 2400);
DISPLAY 0.489362 (-7300 2400);
PAINT SKYBLUE (-7300 2400);
FORCEPROP 2 LAST CDS_LIB pure_quanta
J 0
(-7350 2425);
DISPLAY INVISIBLE (-7350 2425);
FORCEPROP 1 LAST PATH I18
J 0
(-7300 2600);
DISPLAY 0.978723 (-7300 2600);
PAINT WHITE (-7300 2600);
DISPLAY INVISIBLE (-7300 2600);
FORCEPROP 1 LAST PART_NUMBER CS21002FB06
J 0
(-7300 2350);
DISPLAY 0.489362 (-7300 2350);
PAINT SKYBLUE (-7300 2350);
DISPLAY INVISIBLE (-7300 2350);
FORCEADD MOSFET_PCH_GDS_ESD_PROTECTED..1
R 6
(-6700 2250);
FORCEPROP 1 LAST LOCATION PQ13
J 0
(-6525 2100);
DISPLAY 0.489362 (-6525 2100);
PAINT SKYBLUE (-6525 2100);
FORCEPROP 0 LAST $SEC 1
J 0
(-6525 2275);
DISPLAY 0.680851 (-6525 2275);
PAINT MONO (-6525 2275);
DISPLAY INVISIBLE (-6525 2275);
FORCEPROP 0 LAST CDS_SEC 1
J 0
(-6525 2275);
DISPLAY 1.021277 (-6525 2275);
DISPLAY INVISIBLE (-6525 2275);
FORCEPROP 0 LASTPIN (-6675 1950) $PN D
R 1
J 2
(-6685 1940);
DISPLAY 0.489362 (-6685 1940);
PAINT MONO (-6685 1940);
FORCEPROP 0 LASTPIN (-6975 2250) $PN G
J 2
(-6985 2260);
DISPLAY 0.489362 (-6985 2260);
PAINT MONO (-6985 2260);
FORCEPROP 0 LASTPIN (-6675 2550) $PN S
R 1
J 0
(-6685 2560);
DISPLAY 0.489362 (-6685 2560);
PAINT MONO (-6685 2560);
FORCEPROP 1 LAST MATERIAL IC
J 0
(-6525 2252);
DISPLAY 0.489362 (-6525 2252);
PAINT SKYBLUE (-6525 2252);
FORCEPROP 2 LAST VALUE PJA3415AE
J 0
(-6525 2202);
DISPLAY 0.489362 (-6525 2202);
PAINT SKYBLUE (-6525 2202);
FORCEPROP 1 LAST NEEDS_NO_SIZE TRUE
J 0
(-6700 2216);
DISPLAY 0.723404 (-6700 2216);
PAINT GREEN (-6700 2216);
DISPLAY INVISIBLE (-6700 2216);
FORCEPROP 1 LAST CDS_LMAN_SYM_OUTLINE -125,150,125,-150
J 0
(-6700 2250);
DISPLAY 0.468085 (-6700 2250);
PAINT GREEN (-6700 2250);
DISPLAY INVISIBLE (-6700 2250);
FORCEPROP 2 LAST CDS_LIB pure_quanta
J 0
(-6700 2250);
DISPLAY INVISIBLE (-6700 2250);
FORCEPROP 2 LAST PART_TYPE SMLF
J 0
(-6550 2077);
DISPLAY 1.021277 (-6550 2077);
DISPLAY INVISIBLE (-6550 2077);
FORCEPROP 1 LAST PATH I19
J 0
(-6700 2250);
DISPLAY 0.723404 (-6700 2250);
PAINT GREEN (-6700 2250);
DISPLAY INVISIBLE (-6700 2250);
FORCEPROP 1 LAST PART_NUMBER BAM34150008
J 0
(-6525 2152);
DISPLAY 0.489362 (-6525 2152);
PAINT SKYBLUE (-6525 2152);
DISPLAY INVISIBLE (-6525 2152);
FORCEADD Q_RES..1
(-8150 1825);
FORCEPROP 1 LAST LOCATION R8282
J 0
(-8200 1875);
DISPLAY 0.489362 (-8200 1875);
PAINT SKYBLUE (-8200 1875);
FORCEPROP 0 LAST $SEC 1
J 0
(-8200 1900);
DISPLAY 0.680851 (-8200 1900);
PAINT MONO (-8200 1900);
DISPLAY INVISIBLE (-8200 1900);
FORCEPROP 0 LAST CDS_SEC 1
J 0
(-8200 1900);
DISPLAY 1.021277 (-8200 1900);
DISPLAY INVISIBLE (-8200 1900);
FORCEPROP 1 LASTPIN (-8250 1825) $PN 1
J 0
(-8238 1837);
DISPLAY 0.489362 (-8238 1837);
PAINT MONO (-8238 1837);
FORCEPROP 1 LASTPIN (-8050 1825) $PN 2
J 0
(-8088 1837);
DISPLAY 0.489362 (-8088 1837);
PAINT MONO (-8088 1837);
FORCEPROP 1 LAST VALUE 0
J 2
(-8275 1875);
DISPLAY 0.489362 (-8275 1875);
PAINT SKYBLUE (-8275 1875);
FORCEPROP 1 LAST PACK_TYPE 0402LF
J 0
(-8225 1975);
DISPLAY 0.489362 (-8225 1975);
PAINT SKYBLUE (-8225 1975);
FORCEPROP 1 LAST MATERIAL CHIP
J 0
(-8225 2025);
DISPLAY 0.489362 (-8225 2025);
PAINT SKYBLUE (-8225 2025);
FORCEPROP 1 LAST WATTAGE 1/16W
J 0
(-8225 2000);
DISPLAY 0.489362 (-8225 2000);
PAINT SKYBLUE (-8225 2000);
FORCEPROP 1 LAST TOLERANCE 5%
J 0
(-8225 1950);
DISPLAY 0.489362 (-8225 1950);
PAINT SKYBLUE (-8225 1950);
FORCEPROP 2 LAST CDS_LIB pure_quanta
J 0
(-8150 1825);
DISPLAY INVISIBLE (-8150 1825);
FORCEPROP 1 LAST PATH I2
J 0
(-8200 1975);
DISPLAY 0.978723 (-8200 1975);
PAINT WHITE (-8200 1975);
DISPLAY INVISIBLE (-8200 1975);
FORCEPROP 1 LAST PART_NUMBER CS00002JB13
J 0
(-8225 2050);
DISPLAY 0.489362 (-8225 2050);
PAINT SKYBLUE (-8225 2050);
DISPLAY INVISIBLE (-8225 2050);
FORCEADD UNIVERSAL_GND..1
(-6525 800);
FORCEPROP 3 LASTPIN (-6525 850) SIG_NAME GND\g
J 0
(-6515 860);
DISPLAY 0.659574 (-6515 860);
PAINT MONO (-6515 860);
DISPLAY INVISIBLE (-6515 860);
FORCEPROP 2 LAST CDS_LIB pure_quanta_power
J 0
(-6525 800);
DISPLAY INVISIBLE (-6525 800);
FORCEPROP 1 LAST HDL_POWER GND
J 1
(-6500 725);
DISPLAY 0.872340 (-6500 725);
PAINT GREEN (-6500 725);
DISPLAY INVISIBLE (-6500 725);
FORCEPROP 1 LAST PATH I20
J 0
(-6450 800);
DISPLAY 0.872340 (-6450 800);
PAINT AQUA (-6450 800);
DISPLAY INVISIBLE (-6450 800);
FORCEADD Q_RES..2
(-6525 1025);
FORCEPROP 1 LAST LOCATION PR5
J 0
(-6475 1125);
DISPLAY 0.489362 (-6475 1125);
PAINT SKYBLUE (-6475 1125);
FORCEPROP 2 LAST SEC 1
J 0
(-6475 1250);
DISPLAY 0.680851 (-6475 1250);
PAINT MONO (-6475 1250);
DISPLAY INVISIBLE (-6475 1250);
FORCEPROP 1 LASTPIN (-6525 1125) $PN 1
J 0
(-6520 1087);
DISPLAY 0.489362 (-6520 1087);
PAINT MONO (-6520 1087);
FORCEPROP 1 LASTPIN (-6525 925) $PN 2
J 0
(-6520 935);
DISPLAY 0.489362 (-6520 935);
PAINT MONO (-6520 935);
FORCEPROP 1 LAST WATTAGE 1/16W
J 0
(-6475 975);
DISPLAY 0.489362 (-6475 975);
PAINT SKYBLUE (-6475 975);
FORCEPROP 1 LAST MATERIAL CHIP
J 0
(-6475 925);
DISPLAY 0.489362 (-6475 925);
PAINT SKYBLUE (-6475 925);
FORCEPROP 1 LAST PACK_TYPE 0402LF
J 0
(-6475 825);
DISPLAY 0.489362 (-6475 825);
PAINT SKYBLUE (-6475 825);
FORCEPROP 1 LAST TOLERANCE 1%
J 0
(-6475 1025);
DISPLAY 0.489362 (-6475 1025);
PAINT SKYBLUE (-6475 1025);
FORCEPROP 1 LAST VALUE 10K
J 0
(-6475 1075);
DISPLAY 0.489362 (-6475 1075);
PAINT SKYBLUE (-6475 1075);
FORCEPROP 2 LAST CDS_LIB pure_quanta
J 0
(-6525 1025);
DISPLAY INVISIBLE (-6525 1025);
FORCEPROP 2 LAST SEC_TYPE 0402LF
J 0
(-6475 1250);
DISPLAY 1.021277 (-6475 1250);
DISPLAY INVISIBLE (-6475 1250);
FORCEPROP 1 LAST PATH I21
J 0
(-6475 1200);
DISPLAY 0.978723 (-6475 1200);
PAINT WHITE (-6475 1200);
DISPLAY INVISIBLE (-6475 1200);
FORCEPROP 1 LAST PART_NUMBER CS31002FB08
J 0
(-6475 875);
DISPLAY 0.489362 (-6475 875);
PAINT SKYBLUE (-6475 875);
DISPLAY INVISIBLE (-6475 875);
FORCEADD UNIVERSAL_GND..1
(-6050 800);
FORCEPROP 3 LASTPIN (-6050 850) SIG_NAME GND\g
J 0
(-6040 860);
DISPLAY 0.659574 (-6040 860);
PAINT MONO (-6040 860);
DISPLAY INVISIBLE (-6040 860);
FORCEPROP 2 LAST CDS_LIB pure_quanta_power
J 0
(-6050 800);
DISPLAY INVISIBLE (-6050 800);
FORCEPROP 1 LAST HDL_POWER GND
J 1
(-6025 725);
DISPLAY 0.872340 (-6025 725);
PAINT GREEN (-6025 725);
DISPLAY INVISIBLE (-6025 725);
FORCEPROP 1 LAST PATH I22
J 0
(-5975 800);
DISPLAY 0.872340 (-5975 800);
PAINT AQUA (-5975 800);
DISPLAY INVISIBLE (-5975 800);
FORCEADD Q_CAP..1
(-6050 1025);
FORCEPROP 1 LAST LOCATION PC462
J 0
(-6000 1125);
DISPLAY 0.489362 (-6000 1125);
PAINT SKYBLUE (-6000 1125);
FORCEPROP 0 LAST $SEC 1
J 0
(-6000 1150);
DISPLAY 0.680851 (-6000 1150);
PAINT MONO (-6000 1150);
DISPLAY INVISIBLE (-6000 1150);
FORCEPROP 0 LAST CDS_SEC 1
J 0
(-6000 1150);
DISPLAY 1.021277 (-6000 1150);
DISPLAY INVISIBLE (-6000 1150);
FORCEPROP 1 LASTPIN (-6050 1125) $PN 1
J 0
(-6040 1105);
DISPLAY 0.489362 (-6040 1105);
PAINT MONO (-6040 1105);
FORCEPROP 1 LASTPIN (-6050 925) $PN 2
J 0
(-6040 905);
DISPLAY 0.489362 (-6040 905);
PAINT MONO (-6040 905);
FORCEPROP 1 LAST VALUE 0.1UF
J 0
(-6000 1075);
DISPLAY 0.489362 (-6000 1075);
PAINT SKYBLUE (-6000 1075);
FORCEPROP 1 LAST VOLTAGE 25V
J 0
(-6000 1025);
DISPLAY 0.489362 (-6000 1025);
PAINT SKYBLUE (-6000 1025);
FORCEPROP 1 LAST MATERIAL X7R
J 0
(-6000 925);
DISPLAY 0.489362 (-6000 925);
PAINT SKYBLUE (-6000 925);
FORCEPROP 1 LAST PACK_TYPE 0402
J 0
(-6000 825);
DISPLAY 0.489362 (-6000 825);
PAINT SKYBLUE (-6000 825);
FORCEPROP 1 LAST TOLERANCE 10%
J 0
(-6000 975);
DISPLAY 0.489362 (-6000 975);
PAINT SKYBLUE (-6000 975);
FORCEPROP 2 LAST CDS_LIB pure_quanta
J 0
(-6050 1025);
DISPLAY INVISIBLE (-6050 1025);
FORCEPROP 1 LAST PATH I23
J 0
(-6000 1175);
DISPLAY 0.978723 (-6000 1175);
PAINT WHITE (-6000 1175);
DISPLAY INVISIBLE (-6000 1175);
FORCEPROP 1 LAST PART_NUMBER CH4104K1B00
J 0
(-6000 875);
DISPLAY 0.489362 (-6000 875);
PAINT SKYBLUE (-6000 875);
DISPLAY INVISIBLE (-6000 875);
FORCEADD Q_RES..1
(-5900 1400);
FORCEPROP 1 LAST LOCATION R8299
J 0
(-5950 1450);
DISPLAY 0.489362 (-5950 1450);
PAINT SKYBLUE (-5950 1450);
FORCEPROP 0 LAST $SEC 1
J 0
(-5950 1500);
DISPLAY 0.680851 (-5950 1500);
PAINT MONO (-5950 1500);
DISPLAY INVISIBLE (-5950 1500);
FORCEPROP 0 LAST CDS_SEC 1
J 0
(-5950 1500);
DISPLAY 1.021277 (-5950 1500);
DISPLAY INVISIBLE (-5950 1500);
FORCEPROP 1 LASTPIN (-6000 1400) $PN 1
J 0
(-5988 1412);
DISPLAY 0.489362 (-5988 1412);
PAINT MONO (-5988 1412);
FORCEPROP 1 LASTPIN (-5800 1400) $PN 2
J 0
(-5838 1412);
DISPLAY 0.489362 (-5838 1412);
PAINT MONO (-5838 1412);
FORCEPROP 1 LAST MATERIAL CHIP
J 0
(-6150 1325);
DISPLAY 0.489362 (-6150 1325);
PAINT SKYBLUE (-6150 1325);
FORCEPROP 1 LAST WATTAGE 1/16W
J 0
(-5800 1350);
DISPLAY 0.489362 (-5800 1350);
PAINT SKYBLUE (-5800 1350);
FORCEPROP 1 LAST TOLERANCE 5%
J 0
(-5775 1425);
DISPLAY 0.489362 (-5775 1425);
PAINT SKYBLUE (-5775 1425);
FORCEPROP 1 LAST PACK_TYPE 0402LF
J 0
(-5800 1325);
DISPLAY 0.489362 (-5800 1325);
PAINT SKYBLUE (-5800 1325);
FORCEPROP 1 LAST VALUE 33
J 2
(-6025 1425);
DISPLAY 0.489362 (-6025 1425);
PAINT SKYBLUE (-6025 1425);
FORCEPROP 2 LAST CDS_LIB pure_quanta
J 0
(-5900 1400);
DISPLAY INVISIBLE (-5900 1400);
FORCEPROP 1 LAST PATH I24
J 0
(-5950 1550);
DISPLAY 0.978723 (-5950 1550);
PAINT WHITE (-5950 1550);
DISPLAY INVISIBLE (-5950 1550);
FORCEPROP 1 LAST PART_NUMBER CS03302JB10
J 0
(-6150 1350);
DISPLAY 0.489362 (-6150 1350);
PAINT SKYBLUE (-6150 1350);
DISPLAY INVISIBLE (-6150 1350);
FORCEADD VCC_CORE..1
(-5750 1125);
FORCEPROP 3 LASTPIN (-5750 1075) SIG_NAME P12V_AUX\g
J 0
(-5740 1085);
DISPLAY 0.659574 (-5740 1085);
PAINT MONO (-5740 1085);
DISPLAY INVISIBLE (-5740 1085);
FORCEPROP 1 LAST HDL_POWER P12V_AUX
J 1
(-5750 1175);
DISPLAY 0.489362 (-5750 1175);
PAINT GREEN (-5750 1175);
FORCEPROP 2 LAST CDS_LIB pure_quanta_power
J 0
(-5750 1125);
DISPLAY INVISIBLE (-5750 1125);
FORCEPROP 1 LAST PATH I25
J 0
(-5700 1150);
DISPLAY 0.872340 (-5700 1150);
PAINT AQUA (-5700 1150);
DISPLAY INVISIBLE (-5700 1150);
FORCEADD UNIVERSAL_GND..1
(-6675 1575);
FORCEPROP 3 LASTPIN (-6675 1625) SIG_NAME GND\g
J 0
(-6665 1635);
DISPLAY 0.659574 (-6665 1635);
PAINT MONO (-6665 1635);
DISPLAY INVISIBLE (-6665 1635);
FORCEPROP 2 LAST CDS_LIB pure_quanta_power
J 0
(-6675 1575);
DISPLAY INVISIBLE (-6675 1575);
FORCEPROP 1 LAST HDL_POWER GND
J 1
(-6650 1500);
DISPLAY 0.872340 (-6650 1500);
PAINT GREEN (-6650 1500);
DISPLAY INVISIBLE (-6650 1500);
FORCEPROP 1 LAST PATH I26
J 0
(-6600 1575);
DISPLAY 0.872340 (-6600 1575);
PAINT AQUA (-6600 1575);
DISPLAY INVISIBLE (-6600 1575);
FORCEADD Q_RES..2
(-6675 1775);
FORCEPROP 1 LAST LOCATION PR292
J 0
(-6625 1825);
DISPLAY 0.489362 (-6625 1825);
PAINT SKYBLUE (-6625 1825);
FORCEPROP 0 LAST $SEC 1
J 0
(-6625 1850);
DISPLAY 0.680851 (-6625 1850);
PAINT MONO (-6625 1850);
DISPLAY INVISIBLE (-6625 1850);
FORCEPROP 0 LAST CDS_SEC 1
J 0
(-6625 1850);
DISPLAY 1.021277 (-6625 1850);
DISPLAY INVISIBLE (-6625 1850);
FORCEPROP 1 LASTPIN (-6675 1875) $PN 1
J 0
(-6670 1837);
DISPLAY 0.489362 (-6670 1837);
PAINT MONO (-6670 1837);
FORCEPROP 1 LASTPIN (-6675 1675) $PN 2
J 0
(-6670 1685);
DISPLAY 0.489362 (-6670 1685);
PAINT MONO (-6670 1685);
FORCEPROP 1 LAST PACK_TYPE 0402LF
J 0
(-6625 1675);
DISPLAY 0.489362 (-6625 1675);
PAINT SKYBLUE (-6625 1675);
FORCEPROP 1 LAST VALUE 681
J 0
(-6625 1800);
DISPLAY 0.489362 (-6625 1800);
PAINT SKYBLUE (-6625 1800);
FORCEPROP 1 LAST TOLERANCE 1%
J 0
(-6625 1775);
DISPLAY 0.489362 (-6625 1775);
PAINT SKYBLUE (-6625 1775);
FORCEPROP 1 LAST WATTAGE 1/16W
J 0
(-6625 1750);
DISPLAY 0.489362 (-6625 1750);
PAINT SKYBLUE (-6625 1750);
FORCEPROP 1 LAST MATERIAL CHIP
J 0
(-6625 1725);
DISPLAY 0.489362 (-6625 1725);
PAINT SKYBLUE (-6625 1725);
FORCEPROP 2 LAST CDS_LIB pure_quanta
J 0
(-6675 1775);
DISPLAY INVISIBLE (-6675 1775);
FORCEPROP 1 LAST PATH I27
J 0
(-6625 1950);
DISPLAY 0.978723 (-6625 1950);
PAINT WHITE (-6625 1950);
DISPLAY INVISIBLE (-6625 1950);
FORCEPROP 1 LAST PART_NUMBER CS16812FB02
J 0
(-6625 1700);
DISPLAY 0.489362 (-6625 1700);
PAINT SKYBLUE (-6625 1700);
DISPLAY INVISIBLE (-6625 1700);
FORCEADD Q_RES..1
(-5900 1650);
FORCEPROP 1 LAST LOCATION R8298
J 0
(-5950 1700);
DISPLAY 0.489362 (-5950 1700);
PAINT SKYBLUE (-5950 1700);
FORCEPROP 0 LAST $SEC 1
J 0
(-5950 1750);
DISPLAY 0.680851 (-5950 1750);
PAINT MONO (-5950 1750);
DISPLAY INVISIBLE (-5950 1750);
FORCEPROP 0 LAST CDS_SEC 1
J 0
(-5950 1750);
DISPLAY 1.021277 (-5950 1750);
DISPLAY INVISIBLE (-5950 1750);
FORCEPROP 1 LASTPIN (-6000 1650) $PN 1
J 0
(-5988 1662);
DISPLAY 0.489362 (-5988 1662);
PAINT MONO (-5988 1662);
FORCEPROP 1 LASTPIN (-5800 1650) $PN 2
J 0
(-5838 1662);
DISPLAY 0.489362 (-5838 1662);
PAINT MONO (-5838 1662);
FORCEPROP 1 LAST WATTAGE 1/16W
J 0
(-5800 1600);
DISPLAY 0.489362 (-5800 1600);
PAINT SKYBLUE (-5800 1600);
FORCEPROP 1 LAST VALUE 1K
J 2
(-6050 1675);
DISPLAY 0.489362 (-6050 1675);
PAINT SKYBLUE (-6050 1675);
FORCEPROP 1 LAST PACK_TYPE 0402LF
J 0
(-5800 1550);
DISPLAY 0.489362 (-5800 1550);
PAINT SKYBLUE (-5800 1550);
FORCEPROP 1 LAST MATERIAL CHIP
J 0
(-6225 1550);
DISPLAY 0.489362 (-6225 1550);
PAINT SKYBLUE (-6225 1550);
FORCEPROP 1 LAST TOLERANCE 1%
J 0
(-5800 1675);
DISPLAY 0.489362 (-5800 1675);
PAINT SKYBLUE (-5800 1675);
FORCEPROP 2 LAST CDS_LIB pure_quanta
J 0
(-5900 1650);
DISPLAY INVISIBLE (-5900 1650);
FORCEPROP 1 LAST PATH I28
J 0
(-5950 1800);
DISPLAY 0.978723 (-5950 1800);
PAINT WHITE (-5950 1800);
DISPLAY INVISIBLE (-5950 1800);
FORCEPROP 1 LAST PART_NUMBER CS21002FB06
J 0
(-6225 1600);
DISPLAY 0.489362 (-6225 1600);
PAINT SKYBLUE (-6225 1600);
DISPLAY INVISIBLE (-6225 1600);
FORCEADD VCC_CORE..1
(-6175 1800);
FORCEPROP 3 LASTPIN (-6175 1750) SIG_NAME P3V3_AUX\g
J 0
(-6165 1760);
DISPLAY 0.659574 (-6165 1760);
PAINT MONO (-6165 1760);
DISPLAY INVISIBLE (-6165 1760);
FORCEPROP 1 LAST HDL_POWER P3V3_AUX
J 1
(-6175 1850);
DISPLAY 0.489362 (-6175 1850);
PAINT GREEN (-6175 1850);
FORCEPROP 2 LAST CDS_LIB pure_quanta_power
J 0
(-6175 1800);
DISPLAY INVISIBLE (-6175 1800);
FORCEPROP 1 LAST PATH I29
J 0
(-6125 1825);
DISPLAY 0.872340 (-6125 1825);
PAINT AQUA (-6125 1825);
DISPLAY INVISIBLE (-6125 1825);
FORCEADD UNIVERSAL_GND..1
(-8100 5175);
FORCEPROP 3 LASTPIN (-8100 5225) SIG_NAME GND\g
J 0
(-8090 5235);
DISPLAY 0.659574 (-8090 5235);
PAINT MONO (-8090 5235);
DISPLAY INVISIBLE (-8090 5235);
FORCEPROP 2 LAST CDS_LIB pure_quanta_power
J 0
(-8100 5175);
DISPLAY INVISIBLE (-8100 5175);
FORCEPROP 1 LAST HDL_POWER GND
J 1
(-8075 5100);
DISPLAY 0.872340 (-8075 5100);
PAINT GREEN (-8075 5100);
DISPLAY INVISIBLE (-8075 5100);
FORCEPROP 1 LAST PATH I3
J 0
(-8025 5175);
DISPLAY 0.872340 (-8025 5175);
PAINT AQUA (-8025 5175);
DISPLAY INVISIBLE (-8025 5175);
FORCEADD VCC_CORE..1
(-5850 2200);
FORCEPROP 3 LASTPIN (-5850 2150) SIG_NAME PVDD18_S5_P0\g
J 0
(-5840 2160);
DISPLAY 0.659574 (-5840 2160);
PAINT MONO (-5840 2160);
DISPLAY INVISIBLE (-5840 2160);
FORCEPROP 1 LAST HDL_POWER PVDD18_S5_P0
J 1
(-5850 2250);
DISPLAY 0.489362 (-5850 2250);
PAINT GREEN (-5850 2250);
FORCEPROP 2 LAST CDS_LIB pure_quanta_power
J 0
(-5850 2200);
DISPLAY INVISIBLE (-5850 2200);
FORCEPROP 1 LAST PATH I30
J 0
(-5800 2225);
DISPLAY 0.872340 (-5800 2225);
PAINT AQUA (-5800 2225);
DISPLAY INVISIBLE (-5800 2225);
FORCEADD VCC_CORE..1
(-7350 2650);
FORCEPROP 3 LASTPIN (-7350 2600) SIG_NAME P3V3_AUX\g
J 0
(-7340 2610);
DISPLAY 0.659574 (-7340 2610);
PAINT MONO (-7340 2610);
DISPLAY INVISIBLE (-7340 2610);
FORCEPROP 1 LAST HDL_POWER P3V3_AUX
J 1
(-7350 2700);
DISPLAY 0.489362 (-7350 2700);
PAINT GREEN (-7350 2700);
FORCEPROP 2 LAST CDS_LIB pure_quanta_power
J 0
(-7350 2650);
DISPLAY INVISIBLE (-7350 2650);
FORCEPROP 1 LAST PATH I31
J 0
(-7300 2675);
DISPLAY 0.872340 (-7300 2675);
PAINT AQUA (-7300 2675);
DISPLAY INVISIBLE (-7300 2675);
FORCEADD OFFPAGE..4
R 2
(-7375 3100);
FORCEPROP 2 LAST $XR1 193 
J 0
(-7776 3100);
DISPLAY 0.638298 (-7776 3100);
PAINT MONO (-7776 3100);
FORCEPROP 2 LAST $XR0 27 
J 0
(-7656 3100);
DISPLAY 0.638298 (-7656 3100);
PAINT MONO (-7656 3100);
FORCEPROP 2 LAST CDS_LIB standard
J 0
(-7375 3100);
DISPLAY INVISIBLE (-7375 3100);
FORCEPROP 1 LAST OFFPAGE TRUE
J 2
(-7700 2975);
DISPLAY 0.872340 (-7700 2975);
PAINT GREEN (-7700 2975);
DISPLAY INVISIBLE (-7700 2975);
FORCEPROP 1 LAST COMMENT_BODY TRUE
J 2
(-7350 3000);
DISPLAY 0.872340 (-7350 3000);
PAINT GREEN (-7350 3000);
DISPLAY INVISIBLE (-7350 3000);
FORCEPROP 2 LAST PATH I32
J 0
(-7650 3150);
DISPLAY 0.680851 (-7650 3150);
DISPLAY INVISIBLE (-7650 3150);
FORCEADD OFFPAGE..4
R 2
(-7375 3350);
FORCEPROP 2 LAST $XR0 27 
J 0
(-7656 3350);
DISPLAY 0.638298 (-7656 3350);
PAINT MONO (-7656 3350);
FORCEPROP 2 LAST CDS_LIB standard
J 0
(-7375 3350);
DISPLAY INVISIBLE (-7375 3350);
FORCEPROP 1 LAST OFFPAGE TRUE
J 2
(-7700 3225);
DISPLAY 0.872340 (-7700 3225);
PAINT GREEN (-7700 3225);
DISPLAY INVISIBLE (-7700 3225);
FORCEPROP 1 LAST COMMENT_BODY TRUE
J 2
(-7350 3250);
DISPLAY 0.872340 (-7350 3250);
PAINT GREEN (-7350 3250);
DISPLAY INVISIBLE (-7350 3250);
FORCEPROP 2 LAST PATH I33
J 0
(-7650 3400);
DISPLAY 0.680851 (-7650 3400);
DISPLAY INVISIBLE (-7650 3400);
FORCEADD OFFPAGE..4
R 2
(-7375 4200);
FORCEPROP 2 LAST $XR1 193 
J 0
(-7776 4200);
DISPLAY 0.638298 (-7776 4200);
PAINT MONO (-7776 4200);
FORCEPROP 2 LAST $XR0 27 
J 0
(-7656 4200);
DISPLAY 0.638298 (-7656 4200);
PAINT MONO (-7656 4200);
FORCEPROP 2 LAST CDS_LIB standard
J 0
(-7375 4200);
DISPLAY INVISIBLE (-7375 4200);
FORCEPROP 1 LAST OFFPAGE TRUE
J 2
(-7700 4075);
DISPLAY 0.872340 (-7700 4075);
PAINT GREEN (-7700 4075);
DISPLAY INVISIBLE (-7700 4075);
FORCEPROP 1 LAST COMMENT_BODY TRUE
J 2
(-7350 4100);
DISPLAY 0.872340 (-7350 4100);
PAINT GREEN (-7350 4100);
DISPLAY INVISIBLE (-7350 4100);
FORCEPROP 2 LAST PATH I34
J 0
(-7650 4250);
DISPLAY 0.680851 (-7650 4250);
DISPLAY INVISIBLE (-7650 4250);
FORCEADD OFFPAGE..4
R 2
(-7375 4450);
FORCEPROP 2 LAST $XR0 27 
J 0
(-7656 4450);
DISPLAY 0.638298 (-7656 4450);
PAINT MONO (-7656 4450);
FORCEPROP 2 LAST CDS_LIB standard
J 2
(-7375 4450);
DISPLAY INVISIBLE (-7375 4450);
FORCEPROP 1 LAST OFFPAGE TRUE
J 2
(-7700 4325);
DISPLAY 0.872340 (-7700 4325);
PAINT GREEN (-7700 4325);
DISPLAY INVISIBLE (-7700 4325);
FORCEPROP 1 LAST COMMENT_BODY TRUE
J 2
(-7350 4350);
DISPLAY 0.872340 (-7350 4350);
PAINT GREEN (-7350 4350);
DISPLAY INVISIBLE (-7350 4350);
FORCEPROP 2 LAST PATH I35
J 0
(-7650 4500);
DISPLAY 0.680851 (-7650 4500);
DISPLAY INVISIBLE (-7650 4500);
FORCEADD Q_RES..2
(-6625 2925);
FORCEPROP 1 LAST LOCATION PR297
J 0
(-6575 3050);
DISPLAY 0.489362 (-6575 3050);
PAINT SKYBLUE (-6575 3050);
FORCEPROP 0 LAST $SEC 1
J 0
(-6575 3100);
DISPLAY 0.680851 (-6575 3100);
PAINT MONO (-6575 3100);
DISPLAY INVISIBLE (-6575 3100);
FORCEPROP 0 LAST CDS_SEC 1
J 0
(-6575 3100);
DISPLAY 1.021277 (-6575 3100);
DISPLAY INVISIBLE (-6575 3100);
FORCEPROP 1 LASTPIN (-6625 3025) $PN 1
J 0
(-6620 2987);
DISPLAY 0.489362 (-6620 2987);
PAINT MONO (-6620 2987);
FORCEPROP 1 LASTPIN (-6625 2825) $PN 2
J 0
(-6620 2835);
DISPLAY 0.489362 (-6620 2835);
PAINT MONO (-6620 2835);
FORCEPROP 1 LAST PACK_TYPE 0402LF
J 0
(-6575 2750);
DISPLAY 0.489362 (-6575 2750);
PAINT SKYBLUE (-6575 2750);
FORCEPROP 1 LAST VALUE 49.9
J 0
(-6575 3000);
DISPLAY 0.489362 (-6575 3000);
PAINT SKYBLUE (-6575 3000);
FORCEPROP 1 LAST MATERIAL CHIP
J 0
(-6575 2850);
DISPLAY 0.489362 (-6575 2850);
PAINT SKYBLUE (-6575 2850);
FORCEPROP 1 LAST WATTAGE 1/16W
J 0
(-6575 2900);
DISPLAY 0.489362 (-6575 2900);
PAINT SKYBLUE (-6575 2900);
FORCEPROP 1 LAST TOLERANCE 1%
J 0
(-6575 2950);
DISPLAY 0.489362 (-6575 2950);
PAINT SKYBLUE (-6575 2950);
FORCEPROP 2 LAST CDS_LIB pure_quanta
J 0
(-6625 2925);
DISPLAY INVISIBLE (-6625 2925);
FORCEPROP 1 LAST PATH I36
J 0
(-6575 3100);
DISPLAY 0.978723 (-6575 3100);
PAINT WHITE (-6575 3100);
DISPLAY INVISIBLE (-6575 3100);
FORCEPROP 1 LAST PART_NUMBER CS04992FB07
J 0
(-6575 2800);
DISPLAY 0.489362 (-6575 2800);
PAINT SKYBLUE (-6575 2800);
DISPLAY INVISIBLE (-6575 2800);
FORCEADD UNIVERSAL_GND..1
(-6625 2725);
FORCEPROP 3 LASTPIN (-6625 2775) SIG_NAME GND\g
J 0
(-6615 2785);
DISPLAY 0.659574 (-6615 2785);
PAINT MONO (-6615 2785);
DISPLAY INVISIBLE (-6615 2785);
FORCEPROP 2 LAST CDS_LIB pure_quanta_power
J 0
(-6625 2725);
DISPLAY INVISIBLE (-6625 2725);
FORCEPROP 1 LAST HDL_POWER GND
J 1
(-6600 2650);
DISPLAY 0.872340 (-6600 2650);
PAINT GREEN (-6600 2650);
DISPLAY INVISIBLE (-6600 2650);
FORCEPROP 1 LAST PATH I37
J 0
(-6550 2725);
DISPLAY 0.872340 (-6550 2725);
PAINT AQUA (-6550 2725);
DISPLAY INVISIBLE (-6550 2725);
FORCEADD OFFPAGE..5
(-6275 2500);
FORCEPROP 2 LAST $XR0 82 
J 0
(-6499 2500);
DISPLAY 0.638298 (-6499 2500);
PAINT MONO (-6499 2500);
FORCEPROP 2 LAST CDS_LIB standard
J 0
(-6275 2500);
DISPLAY INVISIBLE (-6275 2500);
FORCEPROP 1 LAST OFFPAGE TRUE
J 0
(-5950 2375);
DISPLAY 0.872340 (-5950 2375);
PAINT GREEN (-5950 2375);
DISPLAY INVISIBLE (-5950 2375);
FORCEPROP 1 LAST COMMENT_BODY TRUE
J 0
(-6175 2425);
DISPLAY 0.872340 (-6175 2425);
PAINT GREEN (-6175 2425);
DISPLAY INVISIBLE (-6175 2425);
FORCEPROP 2 LAST PATH I38
J 0
(-6525 2550);
DISPLAY 0.680851 (-6525 2550);
DISPLAY INVISIBLE (-6525 2550);
FORCEADD OFFPAGE..1
(-6275 2650);
FORCEPROP 2 LAST $XR0 78 
J 0
(-6526 2650);
DISPLAY 0.638298 (-6526 2650);
PAINT MONO (-6526 2650);
FORCEPROP 2 LAST CDS_LIB standard
J 0
(-6275 2650);
DISPLAY INVISIBLE (-6275 2650);
FORCEPROP 1 LAST OFFPAGE TRUE
J 0
(-5950 2525);
DISPLAY 0.872340 (-5950 2525);
PAINT GREEN (-5950 2525);
DISPLAY INVISIBLE (-5950 2525);
FORCEPROP 1 LAST COMMENT_BODY TRUE
J 0
(-6150 2550);
DISPLAY 0.872340 (-6150 2550);
PAINT GREEN (-6150 2550);
DISPLAY INVISIBLE (-6150 2550);
FORCEPROP 2 LAST PATH I39
J 0
(-6525 2700);
DISPLAY 0.680851 (-6525 2700);
DISPLAY INVISIBLE (-6525 2700);
FORCEADD Q_RES..2
(-8100 5425);
FORCEPROP 1 LAST LOCATION PR283
J 0
(-8055 5550);
DISPLAY 0.489362 (-8055 5550);
PAINT SKYBLUE (-8055 5550);
FORCEPROP 0 LAST $SEC 1
J 0
(-8050 5575);
DISPLAY 0.680851 (-8050 5575);
PAINT MONO (-8050 5575);
DISPLAY INVISIBLE (-8050 5575);
FORCEPROP 0 LAST CDS_SEC 1
J 0
(-8050 5575);
DISPLAY 1.021277 (-8050 5575);
DISPLAY INVISIBLE (-8050 5575);
FORCEPROP 1 LASTPIN (-8100 5525) $PN 1
J 0
(-8095 5487);
DISPLAY 0.489362 (-8095 5487);
PAINT MONO (-8095 5487);
FORCEPROP 1 LASTPIN (-8100 5325) $PN 2
J 0
(-8095 5335);
DISPLAY 0.489362 (-8095 5335);
PAINT MONO (-8095 5335);
FORCEPROP 1 LAST PACK_TYPE 0402LF
J 0
(-8050 5300);
DISPLAY 0.489362 (-8050 5300);
PAINT SKYBLUE (-8050 5300);
FORCEPROP 1 LAST MATERIAL CHIP
J 0
(-8050 5350);
DISPLAY 0.489362 (-8050 5350);
PAINT SKYBLUE (-8050 5350);
FORCEPROP 1 LAST VALUE 0
J 0
(-8050 5500);
DISPLAY 0.489362 (-8050 5500);
PAINT SKYBLUE (-8050 5500);
FORCEPROP 1 LAST WATTAGE 1/16W
J 0
(-8050 5400);
DISPLAY 0.489362 (-8050 5400);
PAINT SKYBLUE (-8050 5400);
FORCEPROP 1 LAST TOLERANCE 5%
J 0
(-8050 5450);
DISPLAY 0.489362 (-8050 5450);
PAINT SKYBLUE (-8050 5450);
FORCEPROP 2 LAST CDS_LIB pure_quanta
J 0
(-8100 5425);
DISPLAY INVISIBLE (-8100 5425);
FORCEPROP 1 LAST PATH I4
J 0
(-8050 5600);
DISPLAY 0.978723 (-8050 5600);
PAINT WHITE (-8050 5600);
DISPLAY INVISIBLE (-8050 5600);
FORCEPROP 1 LAST PART_NUMBER CS00002JB13
J 0
(-8100 5225);
DISPLAY 0.489362 (-8100 5225);
PAINT SKYBLUE (-8100 5225);
DISPLAY INVISIBLE (-8100 5225);
FORCEADD Q_RES..2
(-6625 3525);
FORCEPROP 1 LAST LOCATION PR296
J 0
(-6575 3650);
DISPLAY 0.489362 (-6575 3650);
PAINT SKYBLUE (-6575 3650);
FORCEPROP 0 LAST $SEC 1
J 0
(-6575 3700);
DISPLAY 0.680851 (-6575 3700);
PAINT MONO (-6575 3700);
DISPLAY INVISIBLE (-6575 3700);
FORCEPROP 0 LAST CDS_SEC 1
J 0
(-6575 3700);
DISPLAY 1.021277 (-6575 3700);
DISPLAY INVISIBLE (-6575 3700);
FORCEPROP 1 LASTPIN (-6625 3625) $PN 1
J 0
(-6620 3587);
DISPLAY 0.489362 (-6620 3587);
PAINT MONO (-6620 3587);
FORCEPROP 1 LASTPIN (-6625 3425) $PN 2
J 0
(-6620 3435);
DISPLAY 0.489362 (-6620 3435);
PAINT MONO (-6620 3435);
FORCEPROP 1 LAST VALUE 49.9
J 0
(-6575 3600);
DISPLAY 0.489362 (-6575 3600);
PAINT SKYBLUE (-6575 3600);
FORCEPROP 1 LAST PACK_TYPE 0402LF
J 0
(-6575 3350);
DISPLAY 0.489362 (-6575 3350);
PAINT SKYBLUE (-6575 3350);
FORCEPROP 1 LAST MATERIAL CHIP
J 0
(-6575 3450);
DISPLAY 0.489362 (-6575 3450);
PAINT SKYBLUE (-6575 3450);
FORCEPROP 1 LAST WATTAGE 1/16W
J 0
(-6575 3500);
DISPLAY 0.489362 (-6575 3500);
PAINT SKYBLUE (-6575 3500);
FORCEPROP 1 LAST TOLERANCE 1%
J 0
(-6575 3550);
DISPLAY 0.489362 (-6575 3550);
PAINT SKYBLUE (-6575 3550);
FORCEPROP 2 LAST CDS_LIB pure_quanta
J 0
(-6625 3525);
DISPLAY INVISIBLE (-6625 3525);
FORCEPROP 1 LAST PATH I40
J 0
(-6575 3700);
DISPLAY 0.978723 (-6575 3700);
PAINT WHITE (-6575 3700);
DISPLAY INVISIBLE (-6575 3700);
FORCEPROP 1 LAST PART_NUMBER CS04992FB07
J 0
(-6575 3400);
DISPLAY 0.489362 (-6575 3400);
PAINT SKYBLUE (-6575 3400);
DISPLAY INVISIBLE (-6575 3400);
FORCEADD VCC_CORE..1
(-6150 2925);
FORCEPROP 3 LASTPIN (-6150 2875) SIG_NAME PVDD18_S5_P0\g
J 0
(-6140 2885);
DISPLAY 0.659574 (-6140 2885);
PAINT MONO (-6140 2885);
DISPLAY INVISIBLE (-6140 2885);
FORCEPROP 1 LAST HDL_POWER PVDD18_S5_P0
J 1
(-6150 2975);
DISPLAY 0.489362 (-6150 2975);
PAINT GREEN (-6150 2975);
FORCEPROP 2 LAST CDS_LIB pure_quanta_power
J 0
(-6150 2925);
DISPLAY INVISIBLE (-6150 2925);
FORCEPROP 1 LAST PATH I41
J 0
(-6100 2950);
DISPLAY 0.872340 (-6100 2950);
PAINT AQUA (-6100 2950);
DISPLAY INVISIBLE (-6100 2950);
FORCEADD Q_RES..1
(-5700 2800);
FORCEPROP 1 LAST LOCATION R8317
J 0
(-6075 2825);
DISPLAY 0.489362 (-6075 2825);
PAINT SKYBLUE (-6075 2825);
FORCEPROP 0 LAST $SEC 1
J 0
(-5950 2900);
DISPLAY 0.680851 (-5950 2900);
PAINT MONO (-5950 2900);
DISPLAY INVISIBLE (-5950 2900);
FORCEPROP 0 LAST CDS_SEC 1
J 0
(-5950 2900);
DISPLAY 1.021277 (-5950 2900);
DISPLAY INVISIBLE (-5950 2900);
FORCEPROP 1 LASTPIN (-5800 2800) $PN 1
J 0
(-5788 2812);
DISPLAY 0.489362 (-5788 2812);
PAINT MONO (-5788 2812);
FORCEPROP 1 LASTPIN (-5600 2800) $PN 2
J 0
(-5638 2812);
DISPLAY 0.489362 (-5638 2812);
PAINT MONO (-5638 2812);
FORCEPROP 1 LAST VALUE 1K
J 2
(-5900 2825);
DISPLAY 0.489362 (-5900 2825);
PAINT SKYBLUE (-5900 2825);
FORCEPROP 1 LAST TOLERANCE 1%
J 0
(-5875 2825);
DISPLAY 0.489362 (-5875 2825);
PAINT SKYBLUE (-5875 2825);
FORCEPROP 1 LAST PACK_TYPE 0402LF
J 0
(-5800 2825);
DISPLAY 0.489362 (-5800 2825);
PAINT SKYBLUE (-5800 2825);
FORCEPROP 1 LAST MATERIAL CHIP
J 0
(-5650 2825);
DISPLAY 0.489362 (-5650 2825);
PAINT SKYBLUE (-5650 2825);
FORCEPROP 1 LAST WATTAGE 1/16W
J 2
(-5425 2825);
DISPLAY 0.489362 (-5425 2825);
PAINT SKYBLUE (-5425 2825);
FORCEPROP 2 LAST CDS_LIB pure_quanta
J 0
(-5700 2800);
DISPLAY INVISIBLE (-5700 2800);
FORCEPROP 1 LAST PATH I42
J 0
(-5750 2950);
DISPLAY 0.978723 (-5750 2950);
PAINT WHITE (-5750 2950);
DISPLAY INVISIBLE (-5750 2950);
FORCEPROP 1 LAST PART_NUMBER CS21002FB06
J 0
(-5950 2875);
DISPLAY 0.489362 (-5950 2875);
PAINT SKYBLUE (-5950 2875);
DISPLAY INVISIBLE (-5950 2875);
FORCEADD VCC_CORE..1
(-6625 3700);
FORCEPROP 3 LASTPIN (-6625 3650) SIG_NAME PVDDCR_SOC_P0\g
J 0
(-6615 3660);
DISPLAY 0.659574 (-6615 3660);
PAINT MONO (-6615 3660);
DISPLAY INVISIBLE (-6615 3660);
FORCEPROP 1 LAST HDL_POWER PVDDCR_SOC_P0
J 1
(-6625 3750);
DISPLAY 0.489362 (-6625 3750);
PAINT GREEN (-6625 3750);
FORCEPROP 2 LAST CDS_LIB pure_quanta_power
J 0
(-6625 3700);
DISPLAY INVISIBLE (-6625 3700);
FORCEPROP 1 LAST PATH I43
J 0
(-6575 3725);
DISPLAY 0.872340 (-6575 3725);
PAINT AQUA (-6575 3725);
DISPLAY INVISIBLE (-6575 3725);
FORCEADD Q_RES..2
(-6625 4025);
FORCEPROP 1 LAST LOCATION PR295
J 0
(-6575 4150);
DISPLAY 0.489362 (-6575 4150);
PAINT SKYBLUE (-6575 4150);
FORCEPROP 0 LAST $SEC 1
J 0
(-6575 4175);
DISPLAY 0.680851 (-6575 4175);
PAINT MONO (-6575 4175);
DISPLAY INVISIBLE (-6575 4175);
FORCEPROP 0 LAST CDS_SEC 1
J 0
(-6575 4175);
DISPLAY 1.021277 (-6575 4175);
DISPLAY INVISIBLE (-6575 4175);
FORCEPROP 1 LASTPIN (-6625 4125) $PN 1
J 0
(-6620 4087);
DISPLAY 0.489362 (-6620 4087);
PAINT MONO (-6620 4087);
FORCEPROP 1 LASTPIN (-6625 3925) $PN 2
J 0
(-6620 3935);
DISPLAY 0.489362 (-6620 3935);
PAINT MONO (-6620 3935);
FORCEPROP 1 LAST WATTAGE 1/16W
J 0
(-6575 4000);
DISPLAY 0.489362 (-6575 4000);
PAINT SKYBLUE (-6575 4000);
FORCEPROP 1 LAST MATERIAL CHIP
J 0
(-6575 3950);
DISPLAY 0.489362 (-6575 3950);
PAINT SKYBLUE (-6575 3950);
FORCEPROP 1 LAST PACK_TYPE 0402LF
J 0
(-6575 3850);
DISPLAY 0.489362 (-6575 3850);
PAINT SKYBLUE (-6575 3850);
FORCEPROP 1 LAST VALUE 49.9
J 0
(-6575 4100);
DISPLAY 0.489362 (-6575 4100);
PAINT SKYBLUE (-6575 4100);
FORCEPROP 1 LAST TOLERANCE 1%
J 0
(-6575 4050);
DISPLAY 0.489362 (-6575 4050);
PAINT SKYBLUE (-6575 4050);
FORCEPROP 2 LAST CDS_LIB pure_quanta
J 0
(-6625 4025);
DISPLAY INVISIBLE (-6625 4025);
FORCEPROP 1 LAST PATH I44
J 0
(-6575 4200);
DISPLAY 0.978723 (-6575 4200);
PAINT WHITE (-6575 4200);
DISPLAY INVISIBLE (-6575 4200);
FORCEPROP 1 LAST PART_NUMBER CS04992FB07
J 0
(-6575 3900);
DISPLAY 0.489362 (-6575 3900);
PAINT SKYBLUE (-6575 3900);
DISPLAY INVISIBLE (-6575 3900);
FORCEADD UNIVERSAL_GND..1
(-6625 3825);
FORCEPROP 3 LASTPIN (-6625 3875) SIG_NAME GND\g
J 0
(-6615 3885);
DISPLAY 0.659574 (-6615 3885);
PAINT MONO (-6615 3885);
DISPLAY INVISIBLE (-6615 3885);
FORCEPROP 2 LAST CDS_LIB pure_quanta_power
J 0
(-6625 3825);
DISPLAY INVISIBLE (-6625 3825);
FORCEPROP 1 LAST HDL_POWER GND
J 1
(-6600 3750);
DISPLAY 0.872340 (-6600 3750);
PAINT GREEN (-6600 3750);
DISPLAY INVISIBLE (-6600 3750);
FORCEPROP 1 LAST PATH I45
J 0
(-6550 3825);
DISPLAY 0.872340 (-6550 3825);
PAINT AQUA (-6550 3825);
DISPLAY INVISIBLE (-6550 3825);
FORCEADD UNIVERSAL_GND..1
(-5250 650);
FORCEPROP 3 LASTPIN (-5250 700) SIG_NAME GND\g
J 0
(-5240 710);
DISPLAY 0.659574 (-5240 710);
PAINT MONO (-5240 710);
DISPLAY INVISIBLE (-5240 710);
FORCEPROP 2 LAST CDS_LIB pure_quanta_power
J 0
(-5250 650);
DISPLAY INVISIBLE (-5250 650);
FORCEPROP 1 LAST HDL_POWER GND
J 1
(-5225 575);
DISPLAY 0.872340 (-5225 575);
PAINT GREEN (-5225 575);
DISPLAY INVISIBLE (-5225 575);
FORCEPROP 1 LAST PATH I46
J 0
(-5175 650);
DISPLAY 0.872340 (-5175 650);
PAINT AQUA (-5175 650);
DISPLAY INVISIBLE (-5175 650);
FORCEADD Q_RES..2
(-5250 850);
FORCEPROP 1 LAST LOCATION PR599
J 0
(-5200 975);
DISPLAY 0.489362 (-5200 975);
PAINT SKYBLUE (-5200 975);
FORCEPROP 0 LAST $SEC 1
J 0
(-5200 1000);
DISPLAY 0.680851 (-5200 1000);
PAINT MONO (-5200 1000);
DISPLAY INVISIBLE (-5200 1000);
FORCEPROP 0 LAST CDS_SEC 1
J 0
(-5200 1000);
DISPLAY 0.680851 (-5200 1000);
DISPLAY INVISIBLE (-5200 1000);
FORCEPROP 1 LASTPIN (-5250 950) $PN 1
J 0
(-5245 912);
DISPLAY 0.787234 (-5245 912);
PAINT MONO (-5245 912);
DISPLAY INVISIBLE (-5245 912);
FORCEPROP 1 LASTPIN (-5250 750) $PN 2
J 0
(-5245 760);
DISPLAY 0.787234 (-5245 760);
PAINT MONO (-5245 760);
DISPLAY INVISIBLE (-5245 760);
FORCEPROP 1 LAST VALUE 4.99K
J 0
(-5200 925);
DISPLAY 0.489362 (-5200 925);
PAINT SKYBLUE (-5200 925);
FORCEPROP 1 LAST TOLERANCE 1%
J 0
(-5200 875);
DISPLAY 0.489362 (-5200 875);
PAINT SKYBLUE (-5200 875);
FORCEPROP 1 LAST MATERIAL EMPTY
J 0
(-5200 775);
DISPLAY 0.489362 (-5200 775);
PAINT RED (-5200 775);
FORCEPROP 1 LAST WATTAGE 1/16W
J 0
(-5200 825);
DISPLAY 0.489362 (-5200 825);
PAINT SKYBLUE (-5200 825);
FORCEPROP 1 LAST PACK_TYPE 0402LF
J 0
(-5200 675);
DISPLAY 0.489362 (-5200 675);
PAINT SKYBLUE (-5200 675);
FORCEPROP 2 LAST CDS_LIB pure_quanta
J 0
(-5250 850);
DISPLAY INVISIBLE (-5250 850);
FORCEPROP 1 LAST PATH I47
J 0
(-5200 1025);
DISPLAY 0.978723 (-5200 1025);
PAINT WHITE (-5200 1025);
DISPLAY INVISIBLE (-5200 1025);
FORCEPROP 1 LAST PART_NUMBER CS24992FB07
J 0
(-5200 725);
DISPLAY 0.489362 (-5200 725);
PAINT SKYBLUE (-5200 725);
DISPLAY INVISIBLE (-5200 725);
FORCEADD Q_RES..1
(-5550 1050);
FORCEPROP 1 LAST LOCATION PR314
J 0
(-5575 1100);
DISPLAY 0.489362 (-5575 1100);
PAINT SKYBLUE (-5575 1100);
FORCEPROP 0 LAST $SEC 1
J 0
(-5600 1150);
DISPLAY 0.680851 (-5600 1150);
PAINT MONO (-5600 1150);
DISPLAY INVISIBLE (-5600 1150);
FORCEPROP 0 LAST CDS_SEC 1
J 0
(-5600 1150);
DISPLAY 1.021277 (-5600 1150);
DISPLAY INVISIBLE (-5600 1150);
FORCEPROP 1 LASTPIN (-5650 1050) $PN 1
J 0
(-5638 1062);
DISPLAY 0.489362 (-5638 1062);
PAINT MONO (-5638 1062);
FORCEPROP 1 LASTPIN (-5450 1050) $PN 2
J 0
(-5488 1062);
DISPLAY 0.489362 (-5488 1062);
PAINT MONO (-5488 1062);
FORCEPROP 1 LAST TOLERANCE 5%
J 0
(-5425 1075);
DISPLAY 0.489362 (-5425 1075);
PAINT SKYBLUE (-5425 1075);
FORCEPROP 1 LAST VALUE 0
J 2
(-5675 1075);
DISPLAY 0.489362 (-5675 1075);
PAINT SKYBLUE (-5675 1075);
FORCEPROP 1 LAST MATERIAL CHIP
J 0
(-5800 975);
DISPLAY 0.489362 (-5800 975);
PAINT SKYBLUE (-5800 975);
FORCEPROP 1 LAST PACK_TYPE 0402LF
J 0
(-5450 975);
DISPLAY 0.489362 (-5450 975);
PAINT SKYBLUE (-5450 975);
FORCEPROP 1 LAST WATTAGE 1/16W
J 0
(-5450 1000);
DISPLAY 0.489362 (-5450 1000);
PAINT SKYBLUE (-5450 1000);
FORCEPROP 2 LAST CDS_LIB pure_quanta
J 0
(-5550 1050);
DISPLAY INVISIBLE (-5550 1050);
FORCEPROP 1 LAST PATH I48
J 0
(-5600 1200);
DISPLAY 0.978723 (-5600 1200);
PAINT WHITE (-5600 1200);
DISPLAY INVISIBLE (-5600 1200);
FORCEPROP 1 LAST PART_NUMBER CS00002JB13
J 0
(-5800 1000);
DISPLAY 0.489362 (-5800 1000);
PAINT SKYBLUE (-5800 1000);
DISPLAY INVISIBLE (-5800 1000);
FORCEADD UNIVERSAL_GND..1
(-4875 650);
FORCEPROP 3 LASTPIN (-4875 700) SIG_NAME GND\g
J 0
(-4865 710);
DISPLAY 0.659574 (-4865 710);
PAINT MONO (-4865 710);
DISPLAY INVISIBLE (-4865 710);
FORCEPROP 2 LAST CDS_LIB pure_quanta_power
J 0
(-4875 650);
DISPLAY INVISIBLE (-4875 650);
FORCEPROP 1 LAST HDL_POWER GND
J 1
(-4850 575);
DISPLAY 0.872340 (-4850 575);
PAINT GREEN (-4850 575);
DISPLAY INVISIBLE (-4850 575);
FORCEPROP 1 LAST PATH I49
J 0
(-4800 650);
DISPLAY 0.872340 (-4800 650);
PAINT AQUA (-4800 650);
DISPLAY INVISIBLE (-4800 650);
FORCEADD UNIVERSAL_GND..1
(-7850 5175);
FORCEPROP 3 LASTPIN (-7850 5225) SIG_NAME GND\g
J 0
(-7840 5235);
DISPLAY 0.659574 (-7840 5235);
PAINT MONO (-7840 5235);
DISPLAY INVISIBLE (-7840 5235);
FORCEPROP 2 LAST CDS_LIB pure_quanta_power
J 0
(-7850 5175);
DISPLAY INVISIBLE (-7850 5175);
FORCEPROP 1 LAST HDL_POWER GND
J 1
(-7825 5100);
DISPLAY 0.872340 (-7825 5100);
PAINT GREEN (-7825 5100);
DISPLAY INVISIBLE (-7825 5100);
FORCEPROP 1 LAST PATH I5
J 0
(-7775 5175);
DISPLAY 0.872340 (-7775 5175);
PAINT AQUA (-7775 5175);
DISPLAY INVISIBLE (-7775 5175);
FORCEADD Q_CAP..1
(-4875 875);
FORCEPROP 1 LAST LOCATION PC7
J 0
(-4825 975);
DISPLAY 0.489362 (-4825 975);
PAINT SKYBLUE (-4825 975);
FORCEPROP 2 LAST SEC 1
J 0
(-4825 1075);
DISPLAY 0.680851 (-4825 1075);
PAINT MONO (-4825 1075);
DISPLAY INVISIBLE (-4825 1075);
FORCEPROP 1 LASTPIN (-4875 975) $PN 1
J 0
(-4865 955);
DISPLAY 0.489362 (-4865 955);
PAINT MONO (-4865 955);
FORCEPROP 1 LASTPIN (-4875 775) $PN 2
J 0
(-4865 755);
DISPLAY 0.489362 (-4865 755);
PAINT MONO (-4865 755);
FORCEPROP 1 LAST MATERIAL X7R
J 0
(-4825 775);
DISPLAY 0.489362 (-4825 775);
PAINT SKYBLUE (-4825 775);
FORCEPROP 1 LAST TOLERANCE 10%
J 0
(-4825 825);
DISPLAY 0.489362 (-4825 825);
PAINT SKYBLUE (-4825 825);
FORCEPROP 1 LAST VALUE 0.1UF
J 0
(-4825 925);
DISPLAY 0.489362 (-4825 925);
PAINT SKYBLUE (-4825 925);
FORCEPROP 1 LAST VOLTAGE 25V
J 0
(-4825 875);
DISPLAY 0.489362 (-4825 875);
PAINT SKYBLUE (-4825 875);
FORCEPROP 1 LAST PACK_TYPE 0402
J 0
(-4825 675);
DISPLAY 0.489362 (-4825 675);
PAINT SKYBLUE (-4825 675);
FORCEPROP 2 LAST CDS_LIB pure_quanta
J 0
(-4875 875);
DISPLAY INVISIBLE (-4875 875);
FORCEPROP 2 LAST SEC_TYPE 0402
J 0
(-4825 1075);
DISPLAY 1.021277 (-4825 1075);
DISPLAY INVISIBLE (-4825 1075);
FORCEPROP 1 LAST PATH I50
J 0
(-4825 1025);
DISPLAY 0.978723 (-4825 1025);
PAINT WHITE (-4825 1025);
DISPLAY INVISIBLE (-4825 1025);
FORCEPROP 1 LAST PART_NUMBER CH4104K1B00
J 0
(-4825 725);
DISPLAY 0.489362 (-4825 725);
PAINT SKYBLUE (-4825 725);
DISPLAY INVISIBLE (-4825 725);
FORCEADD Q_CAP..2
(-5225 1650);
FORCEPROP 1 LAST LOCATION C465
J 1
(-5225 1700);
DISPLAY 0.489362 (-5225 1700);
PAINT SKYBLUE (-5225 1700);
FORCEPROP 0 LAST $SEC 1
J 0
(-5225 1800);
DISPLAY 0.680851 (-5225 1800);
PAINT MONO (-5225 1800);
DISPLAY INVISIBLE (-5225 1800);
FORCEPROP 0 LAST CDS_SEC 1
J 0
(-5225 1800);
DISPLAY 1.021277 (-5225 1800);
DISPLAY INVISIBLE (-5225 1800);
FORCEPROP 1 LASTPIN (-5325 1650) $PN 1
J 0
(-5335 1665);
DISPLAY 0.489362 (-5335 1665);
PAINT MONO (-5335 1665);
FORCEPROP 1 LASTPIN (-5125 1650) $PN 2
J 0
(-5140 1665);
DISPLAY 0.489362 (-5140 1665);
PAINT MONO (-5140 1665);
FORCEPROP 1 LAST TOLERANCE 5%
J 0
(-5100 1525);
DISPLAY 0.489362 (-5100 1525);
PAINT SKYBLUE (-5100 1525);
FORCEPROP 1 LAST VOLTAGE 50V
J 0
(-5100 1700);
DISPLAY 0.489362 (-5100 1700);
PAINT SKYBLUE (-5100 1700);
FORCEPROP 1 LAST PACK_TYPE 0402
J 0
(-5100 1575);
DISPLAY 0.489362 (-5100 1575);
PAINT SKYBLUE (-5100 1575);
FORCEPROP 1 LAST VALUE 1000PF
J 2
(-5350 1700);
DISPLAY 0.489362 (-5350 1700);
PAINT SKYBLUE (-5350 1700);
FORCEPROP 1 LAST MATERIAL EMPTY
J 0
(-5500 1525);
DISPLAY 0.489362 (-5500 1525);
PAINT RED (-5500 1525);
FORCEPROP 2 LAST CDS_LIB pure_quanta
J 0
(-5225 1650);
DISPLAY INVISIBLE (-5225 1650);
FORCEPROP 1 LAST PATH I51
J 0
(-5225 1850);
DISPLAY 0.978723 (-5225 1850);
PAINT WHITE (-5225 1850);
DISPLAY INVISIBLE (-5225 1850);
FORCEPROP 1 LAST PART_NUMBER TMP_QCH21006JB10
J 1
(-5375 1575);
DISPLAY 0.489362 (-5375 1575);
PAINT SKYBLUE (-5375 1575);
DISPLAY INVISIBLE (-5375 1575);
FORCEADD Q_CAP..2
(-5250 2125);
FORCEPROP 1 LAST LOCATION PC466
J 1
(-5575 2175);
DISPLAY 0.489362 (-5575 2175);
PAINT SKYBLUE (-5575 2175);
FORCEPROP 0 LAST $SEC 1
J 0
(-4675 2200);
DISPLAY 0.680851 (-4675 2200);
PAINT MONO (-4675 2200);
DISPLAY INVISIBLE (-4675 2200);
FORCEPROP 0 LAST CDS_SEC 1
J 0
(-4675 2200);
DISPLAY 1.021277 (-4675 2200);
DISPLAY INVISIBLE (-4675 2200);
FORCEPROP 1 LASTPIN (-5350 2125) $PN 1
J 0
(-5360 2140);
DISPLAY 0.489362 (-5360 2140);
PAINT MONO (-5360 2140);
FORCEPROP 1 LASTPIN (-5150 2125) $PN 2
J 0
(-5165 2140);
DISPLAY 0.489362 (-5165 2140);
PAINT MONO (-5165 2140);
FORCEPROP 1 LAST TOLERANCE 10%
J 2
(-4675 2175);
DISPLAY 0.489362 (-4675 2175);
PAINT SKYBLUE (-4675 2175);
FORCEPROP 1 LAST MATERIAL X7R
J 0
(-5275 2175);
DISPLAY 0.489362 (-5275 2175);
PAINT SKYBLUE (-5275 2175);
FORCEPROP 1 LAST VOLTAGE 6.3V
J 0
(-5400 2175);
DISPLAY 0.489362 (-5400 2175);
PAINT SKYBLUE (-5400 2175);
FORCEPROP 1 LAST PACK_TYPE 0402
J 1
(-4825 2175);
DISPLAY 0.489362 (-4825 2175);
PAINT SKYBLUE (-4825 2175);
FORCEPROP 1 LAST VALUE 1UF
J 2
(-5450 2175);
DISPLAY 0.489362 (-5450 2175);
PAINT SKYBLUE (-5450 2175);
FORCEPROP 2 LAST CDS_LIB pure_quanta
J 0
(-5250 2125);
DISPLAY INVISIBLE (-5250 2125);
FORCEPROP 1 LAST PATH I52
J 0
(-5250 2325);
DISPLAY 0.978723 (-5250 2325);
PAINT WHITE (-5250 2325);
DISPLAY INVISIBLE (-5250 2325);
FORCEPROP 1 LAST PART_NUMBER CH5101K1B01
J 1
(-5025 2175);
DISPLAY 0.489362 (-5025 2175);
PAINT SKYBLUE (-5025 2175);
DISPLAY INVISIBLE (-5025 2175);
FORCEADD UNIVERSAL_GND..1
(-4900 1525);
FORCEPROP 3 LASTPIN (-4900 1575) SIG_NAME GND\g
J 0
(-4890 1585);
DISPLAY 0.659574 (-4890 1585);
PAINT MONO (-4890 1585);
DISPLAY INVISIBLE (-4890 1585);
FORCEPROP 2 LAST CDS_LIB pure_quanta_power
J 0
(-4900 1525);
DISPLAY INVISIBLE (-4900 1525);
FORCEPROP 1 LAST HDL_POWER GND
J 1
(-4875 1450);
DISPLAY 0.872340 (-4875 1450);
PAINT GREEN (-4875 1450);
DISPLAY INVISIBLE (-4875 1450);
FORCEPROP 1 LAST PATH I53
J 0
(-4825 1525);
DISPLAY 0.872340 (-4825 1525);
PAINT AQUA (-4825 1525);
DISPLAY INVISIBLE (-4825 1525);
FORCEADD Q_RES..1
(-5000 2375);
FORCEPROP 1 LAST LOCATION R8313
J 0
(-5050 2325);
DISPLAY 0.489362 (-5050 2325);
PAINT SKYBLUE (-5050 2325);
FORCEPROP 0 LAST $SEC 1
J 0
(-5250 2475);
DISPLAY 0.680851 (-5250 2475);
PAINT MONO (-5250 2475);
DISPLAY INVISIBLE (-5250 2475);
FORCEPROP 0 LAST CDS_SEC 1
J 0
(-5250 2475);
DISPLAY 1.021277 (-5250 2475);
DISPLAY INVISIBLE (-5250 2475);
FORCEPROP 1 LASTPIN (-5100 2375) $PN 1
J 0
(-5088 2387);
DISPLAY 0.489362 (-5088 2387);
PAINT MONO (-5088 2387);
FORCEPROP 1 LASTPIN (-4900 2375) $PN 2
J 0
(-4938 2387);
DISPLAY 0.489362 (-4938 2387);
PAINT MONO (-4938 2387);
FORCEPROP 1 LAST PACK_TYPE 0402LF
J 0
(-5100 2400);
DISPLAY 0.489362 (-5100 2400);
PAINT SKYBLUE (-5100 2400);
FORCEPROP 1 LAST TOLERANCE 1%
J 0
(-5175 2400);
DISPLAY 0.489362 (-5175 2400);
PAINT SKYBLUE (-5175 2400);
FORCEPROP 1 LAST VALUE 1K
J 2
(-5200 2400);
DISPLAY 0.489362 (-5200 2400);
PAINT SKYBLUE (-5200 2400);
FORCEPROP 1 LAST WATTAGE 1/16W
J 2
(-4725 2400);
DISPLAY 0.489362 (-4725 2400);
PAINT SKYBLUE (-4725 2400);
FORCEPROP 1 LAST MATERIAL CHIP
J 0
(-4950 2400);
DISPLAY 0.489362 (-4950 2400);
PAINT SKYBLUE (-4950 2400);
FORCEPROP 2 LAST CDS_LIB pure_quanta
J 0
(-5000 2375);
DISPLAY INVISIBLE (-5000 2375);
FORCEPROP 1 LAST PATH I54
J 0
(-5050 2525);
DISPLAY 0.978723 (-5050 2525);
PAINT WHITE (-5050 2525);
DISPLAY INVISIBLE (-5050 2525);
FORCEPROP 1 LAST PART_NUMBER CS21002FB06
J 0
(-5250 2450);
DISPLAY 0.489362 (-5250 2450);
PAINT SKYBLUE (-5250 2450);
DISPLAY INVISIBLE (-5250 2450);
FORCEADD UNIVERSAL_GND..1
R 1
(-4850 2125);
FORCEPROP 3 LASTPIN (-4900 2125) SIG_NAME GND\g
J 0
(-4890 2135);
DISPLAY 0.659574 (-4890 2135);
PAINT MONO (-4890 2135);
DISPLAY INVISIBLE (-4890 2135);
FORCEPROP 2 LAST CDS_LIB pure_quanta_power
J 0
(-4850 2125);
DISPLAY INVISIBLE (-4850 2125);
FORCEPROP 1 LAST HDL_POWER GND
R 1
J 1
(-4775 2150);
DISPLAY 0.872340 (-4775 2150);
PAINT GREEN (-4775 2150);
DISPLAY INVISIBLE (-4775 2150);
FORCEPROP 1 LAST PATH I55
R 1
J 0
(-4850 2200);
DISPLAY 0.872340 (-4850 2200);
PAINT AQUA (-4850 2200);
DISPLAY INVISIBLE (-4850 2200);
FORCEADD UNIVERSAL_GND..1
(-4675 850);
FORCEPROP 3 LASTPIN (-4675 900) SIG_NAME GND\g
J 0
(-4665 910);
DISPLAY 0.659574 (-4665 910);
PAINT MONO (-4665 910);
DISPLAY INVISIBLE (-4665 910);
FORCEPROP 2 LAST CDS_LIB pure_quanta_power
J 0
(-4675 850);
DISPLAY INVISIBLE (-4675 850);
FORCEPROP 1 LAST HDL_POWER GND
J 1
(-4650 775);
DISPLAY 0.872340 (-4650 775);
PAINT GREEN (-4650 775);
DISPLAY INVISIBLE (-4650 775);
FORCEPROP 1 LAST PATH I56
J 0
(-4600 850);
DISPLAY 0.872340 (-4600 850);
PAINT AQUA (-4600 850);
DISPLAY INVISIBLE (-4600 850);
FORCEADD Q_RES..1
(-5550 2650);
FORCEPROP 1 LAST LOCATION R315
J 0
(-5600 2700);
DISPLAY 0.489362 (-5600 2700);
PAINT SKYBLUE (-5600 2700);
FORCEPROP 0 LAST $SEC 1
J 0
(-5600 2725);
DISPLAY 0.680851 (-5600 2725);
PAINT MONO (-5600 2725);
DISPLAY INVISIBLE (-5600 2725);
FORCEPROP 0 LAST CDS_SEC 1
J 0
(-5600 2725);
DISPLAY 1.021277 (-5600 2725);
DISPLAY INVISIBLE (-5600 2725);
FORCEPROP 1 LASTPIN (-5650 2650) $PN 1
J 0
(-5638 2662);
DISPLAY 0.489362 (-5638 2662);
PAINT MONO (-5638 2662);
FORCEPROP 1 LASTPIN (-5450 2650) $PN 2
J 0
(-5488 2662);
DISPLAY 0.489362 (-5488 2662);
PAINT MONO (-5488 2662);
FORCEPROP 1 LAST TOLERANCE 1%
J 0
(-5450 2600);
DISPLAY 0.489362 (-5450 2600);
PAINT SKYBLUE (-5450 2600);
FORCEPROP 1 LAST VALUE 49.9
J 2
(-5500 2600);
DISPLAY 0.489362 (-5500 2600);
PAINT SKYBLUE (-5500 2600);
FORCEPROP 1 LAST PACK_TYPE 0402LF
J 0
(-5375 2600);
DISPLAY 0.489362 (-5375 2600);
PAINT SKYBLUE (-5375 2600);
FORCEPROP 1 LAST WATTAGE 1/16W
J 2
(-5625 2600);
DISPLAY 0.489362 (-5625 2600);
PAINT SKYBLUE (-5625 2600);
FORCEPROP 1 LAST MATERIAL CHIP
J 0
(-5875 2600);
DISPLAY 0.489362 (-5875 2600);
PAINT SKYBLUE (-5875 2600);
FORCEPROP 2 LAST CDS_LIB pure_quanta
J 0
(-5550 2650);
DISPLAY INVISIBLE (-5550 2650);
FORCEPROP 1 LAST PATH I57
J 0
(-5600 2800);
DISPLAY 0.978723 (-5600 2800);
PAINT WHITE (-5600 2800);
DISPLAY INVISIBLE (-5600 2800);
FORCEPROP 1 LAST PART_NUMBER CS04992FB07
J 0
(-6225 2600);
DISPLAY 0.489362 (-6225 2600);
PAINT SKYBLUE (-6225 2600);
DISPLAY INVISIBLE (-6225 2600);
FORCEADD Q_RES..1
(-5550 2500);
FORCEPROP 1 LAST LOCATION R8301
J 0
(-5600 2550);
DISPLAY 0.489362 (-5600 2550);
PAINT SKYBLUE (-5600 2550);
FORCEPROP 0 LAST $SEC 1
J 0
(-5600 2575);
DISPLAY 0.680851 (-5600 2575);
PAINT MONO (-5600 2575);
DISPLAY INVISIBLE (-5600 2575);
FORCEPROP 0 LAST CDS_SEC 1
J 0
(-5600 2575);
DISPLAY 1.021277 (-5600 2575);
DISPLAY INVISIBLE (-5600 2575);
FORCEPROP 1 LASTPIN (-5650 2500) $PN 1
J 0
(-5638 2512);
DISPLAY 0.489362 (-5638 2512);
PAINT MONO (-5638 2512);
FORCEPROP 1 LASTPIN (-5450 2500) $PN 2
J 0
(-5488 2512);
DISPLAY 0.489362 (-5488 2512);
PAINT MONO (-5488 2512);
FORCEPROP 1 LAST VALUE 0
J 2
(-5550 2450);
DISPLAY 0.489362 (-5550 2450);
PAINT SKYBLUE (-5550 2450);
FORCEPROP 1 LAST WATTAGE 1/16W
J 2
(-5625 2450);
DISPLAY 0.489362 (-5625 2450);
PAINT SKYBLUE (-5625 2450);
FORCEPROP 1 LAST MATERIAL CHIP
J 0
(-5875 2450);
DISPLAY 0.489362 (-5875 2450);
PAINT SKYBLUE (-5875 2450);
FORCEPROP 1 LAST TOLERANCE 5%
J 0
(-5525 2450);
DISPLAY 0.489362 (-5525 2450);
PAINT SKYBLUE (-5525 2450);
FORCEPROP 1 LAST PACK_TYPE 0402LF
J 0
(-5450 2450);
DISPLAY 0.489362 (-5450 2450);
PAINT SKYBLUE (-5450 2450);
FORCEPROP 2 LAST CDS_LIB pure_quanta
J 0
(-5550 2500);
DISPLAY INVISIBLE (-5550 2500);
FORCEPROP 1 LAST PATH I58
J 0
(-5600 2650);
DISPLAY 0.978723 (-5600 2650);
PAINT WHITE (-5600 2650);
DISPLAY INVISIBLE (-5600 2650);
FORCEPROP 1 LAST PART_NUMBER CS00002JB13
J 0
(-6225 2450);
DISPLAY 0.489362 (-6225 2450);
PAINT SKYBLUE (-6225 2450);
DISPLAY INVISIBLE (-6225 2450);
FORCEADD Q_RES..1
(-5525 3350);
FORCEPROP 1 LAST LOCATION PR307
J 0
(-5575 3400);
DISPLAY 0.489362 (-5575 3400);
PAINT SKYBLUE (-5575 3400);
FORCEPROP 0 LAST $SEC 1
J 0
(-5575 3450);
DISPLAY 0.680851 (-5575 3450);
PAINT MONO (-5575 3450);
DISPLAY INVISIBLE (-5575 3450);
FORCEPROP 0 LAST CDS_SEC 1
J 0
(-5575 3450);
DISPLAY 1.021277 (-5575 3450);
DISPLAY INVISIBLE (-5575 3450);
FORCEPROP 1 LASTPIN (-5625 3350) $PN 1
J 0
(-5613 3362);
DISPLAY 0.489362 (-5613 3362);
PAINT MONO (-5613 3362);
FORCEPROP 1 LASTPIN (-5425 3350) $PN 2
J 0
(-5463 3362);
DISPLAY 0.489362 (-5463 3362);
PAINT MONO (-5463 3362);
FORCEPROP 1 LAST VALUE 0
J 2
(-5650 3375);
DISPLAY 0.489362 (-5650 3375);
PAINT SKYBLUE (-5650 3375);
FORCEPROP 1 LAST MATERIAL CHIP
J 0
(-5850 3275);
DISPLAY 0.489362 (-5850 3275);
PAINT SKYBLUE (-5850 3275);
FORCEPROP 1 LAST TOLERANCE 5%
J 0
(-5400 3375);
DISPLAY 0.489362 (-5400 3375);
PAINT SKYBLUE (-5400 3375);
FORCEPROP 1 LAST WATTAGE 1/16W
J 0
(-5425 3300);
DISPLAY 0.489362 (-5425 3300);
PAINT SKYBLUE (-5425 3300);
FORCEPROP 1 LAST PACK_TYPE 0402LF
J 0
(-5425 3275);
DISPLAY 0.489362 (-5425 3275);
PAINT SKYBLUE (-5425 3275);
FORCEPROP 2 LAST CDS_LIB pure_quanta
J 0
(-5525 3350);
DISPLAY INVISIBLE (-5525 3350);
FORCEPROP 1 LAST PATH I59
J 0
(-5575 3500);
DISPLAY 0.978723 (-5575 3500);
PAINT WHITE (-5575 3500);
DISPLAY INVISIBLE (-5575 3500);
FORCEPROP 1 LAST PART_NUMBER CS00002JB13
J 0
(-5850 3300);
DISPLAY 0.489362 (-5850 3300);
PAINT SKYBLUE (-5850 3300);
DISPLAY INVISIBLE (-5850 3300);
FORCEADD Q_RES..2
(-7850 5425);
FORCEPROP 1 LAST LOCATION R8286
J 0
(-7800 5550);
DISPLAY 0.489362 (-7800 5550);
PAINT SKYBLUE (-7800 5550);
FORCEPROP 0 LAST $SEC 1
J 0
(-7800 5575);
DISPLAY 0.680851 (-7800 5575);
PAINT MONO (-7800 5575);
DISPLAY INVISIBLE (-7800 5575);
FORCEPROP 0 LAST CDS_SEC 1
J 0
(-7800 5575);
DISPLAY 1.021277 (-7800 5575);
DISPLAY INVISIBLE (-7800 5575);
FORCEPROP 1 LASTPIN (-7850 5525) $PN 1
J 0
(-7845 5487);
DISPLAY 0.489362 (-7845 5487);
PAINT MONO (-7845 5487);
FORCEPROP 1 LASTPIN (-7850 5325) $PN 2
J 0
(-7845 5335);
DISPLAY 0.489362 (-7845 5335);
PAINT MONO (-7845 5335);
FORCEPROP 1 LAST PACK_TYPE 0402LF
J 0
(-7800 5300);
DISPLAY 0.489362 (-7800 5300);
PAINT SKYBLUE (-7800 5300);
FORCEPROP 1 LAST MATERIAL EMPTY
J 0
(-7800 5350);
DISPLAY 0.489362 (-7800 5350);
PAINT RED (-7800 5350);
FORCEPROP 1 LAST TOLERANCE 1%
J 0
(-7800 5450);
DISPLAY 0.489362 (-7800 5450);
PAINT SKYBLUE (-7800 5450);
FORCEPROP 1 LAST VALUE 1K
J 0
(-7800 5500);
DISPLAY 0.489362 (-7800 5500);
PAINT SKYBLUE (-7800 5500);
FORCEPROP 1 LAST WATTAGE 1/16W
J 0
(-7800 5400);
DISPLAY 0.489362 (-7800 5400);
PAINT SKYBLUE (-7800 5400);
FORCEPROP 2 LAST CDS_LIB pure_quanta
J 0
(-7850 5425);
DISPLAY INVISIBLE (-7850 5425);
FORCEPROP 1 LAST PATH I6
J 0
(-7800 5600);
DISPLAY 0.978723 (-7800 5600);
PAINT WHITE (-7800 5600);
DISPLAY INVISIBLE (-7800 5600);
FORCEPROP 1 LAST PART_NUMBER CS21002FB06
J 0
(-7810 5300);
DISPLAY 0.489362 (-7810 5300);
PAINT SKYBLUE (-7810 5300);
DISPLAY INVISIBLE (-7810 5300);
FORCEADD Q_CAP..1
(-5250 3225);
FORCEPROP 1 LAST LOCATION PC464
J 0
(-5200 3275);
DISPLAY 0.489362 (-5200 3275);
PAINT SKYBLUE (-5200 3275);
FORCEPROP 0 LAST $SEC 1
J 0
(-5200 3375);
DISPLAY 0.680851 (-5200 3375);
PAINT MONO (-5200 3375);
DISPLAY INVISIBLE (-5200 3375);
FORCEPROP 0 LAST CDS_SEC 1
J 0
(-5200 3375);
DISPLAY 1.021277 (-5200 3375);
DISPLAY INVISIBLE (-5200 3375);
FORCEPROP 1 LASTPIN (-5250 3325) $PN 1
J 0
(-5240 3305);
DISPLAY 0.489362 (-5240 3305);
PAINT MONO (-5240 3305);
FORCEPROP 1 LASTPIN (-5250 3125) $PN 2
J 0
(-5240 3105);
DISPLAY 0.489362 (-5240 3105);
PAINT MONO (-5240 3105);
FORCEPROP 1 LAST VALUE 3300PF
J 0
(-5200 3250);
DISPLAY 0.489362 (-5200 3250);
PAINT SKYBLUE (-5200 3250);
FORCEPROP 1 LAST VOLTAGE 50V
J 0
(-5200 3225);
DISPLAY 0.489362 (-5200 3225);
PAINT SKYBLUE (-5200 3225);
FORCEPROP 1 LAST TOLERANCE 10%
J 0
(-5200 3200);
DISPLAY 0.489362 (-5200 3200);
PAINT SKYBLUE (-5200 3200);
FORCEPROP 1 LAST MATERIAL X7R
J 0
(-5200 3175);
DISPLAY 0.489362 (-5200 3175);
PAINT SKYBLUE (-5200 3175);
FORCEPROP 1 LAST PACK_TYPE 0402
J 0
(-5200 3125);
DISPLAY 0.489362 (-5200 3125);
PAINT SKYBLUE (-5200 3125);
FORCEPROP 2 LAST CDS_LIB pure_quanta
J 0
(-5250 3225);
DISPLAY INVISIBLE (-5250 3225);
FORCEPROP 1 LAST PATH I60
J 0
(-5200 3375);
DISPLAY 0.978723 (-5200 3375);
PAINT WHITE (-5200 3375);
DISPLAY INVISIBLE (-5200 3375);
FORCEPROP 1 LAST PART_NUMBER TMP_QCH2336K1B12
J 0
(-5200 3150);
DISPLAY 0.489362 (-5200 3150);
PAINT SKYBLUE (-5200 3150);
DISPLAY INVISIBLE (-5200 3150);
FORCEADD Q_RES..1
(-5600 4450);
FORCEPROP 1 LAST LOCATION PR306
J 0
(-5650 4500);
DISPLAY 0.489362 (-5650 4500);
PAINT SKYBLUE (-5650 4500);
FORCEPROP 0 LAST $SEC 1
J 0
(-5650 4525);
DISPLAY 0.680851 (-5650 4525);
PAINT MONO (-5650 4525);
DISPLAY INVISIBLE (-5650 4525);
FORCEPROP 0 LAST CDS_SEC 1
J 0
(-5650 4525);
DISPLAY 1.021277 (-5650 4525);
DISPLAY INVISIBLE (-5650 4525);
FORCEPROP 1 LASTPIN (-5700 4450) $PN 1
J 0
(-5688 4462);
DISPLAY 0.489362 (-5688 4462);
PAINT MONO (-5688 4462);
FORCEPROP 1 LASTPIN (-5500 4450) $PN 2
J 0
(-5538 4462);
DISPLAY 0.489362 (-5538 4462);
PAINT MONO (-5538 4462);
FORCEPROP 1 LAST TOLERANCE 5%
J 0
(-5475 4475);
DISPLAY 0.489362 (-5475 4475);
PAINT SKYBLUE (-5475 4475);
FORCEPROP 1 LAST VALUE 0
J 2
(-5725 4475);
DISPLAY 0.489362 (-5725 4475);
PAINT SKYBLUE (-5725 4475);
FORCEPROP 1 LAST WATTAGE 1/16W
J 0
(-5500 4400);
DISPLAY 0.489362 (-5500 4400);
PAINT SKYBLUE (-5500 4400);
FORCEPROP 1 LAST MATERIAL CHIP
J 0
(-5925 4375);
DISPLAY 0.489362 (-5925 4375);
PAINT SKYBLUE (-5925 4375);
FORCEPROP 1 LAST PACK_TYPE 0402LF
J 0
(-5500 4375);
DISPLAY 0.489362 (-5500 4375);
PAINT SKYBLUE (-5500 4375);
FORCEPROP 2 LAST CDS_LIB pure_quanta
J 0
(-5600 4450);
DISPLAY INVISIBLE (-5600 4450);
FORCEPROP 1 LAST PATH I61
J 0
(-5650 4600);
DISPLAY 0.978723 (-5650 4600);
PAINT WHITE (-5650 4600);
DISPLAY INVISIBLE (-5650 4600);
FORCEPROP 1 LAST PART_NUMBER CS00002JB13
J 0
(-5925 4400);
DISPLAY 0.489362 (-5925 4400);
PAINT SKYBLUE (-5925 4400);
DISPLAY INVISIBLE (-5925 4400);
FORCEADD Q_CAP..1
(-5325 4325);
FORCEPROP 1 LAST LOCATION PC463
J 0
(-5275 4375);
DISPLAY 0.489362 (-5275 4375);
PAINT SKYBLUE (-5275 4375);
FORCEPROP 0 LAST $SEC 1
J 0
(-5275 4400);
DISPLAY 0.680851 (-5275 4400);
PAINT MONO (-5275 4400);
DISPLAY INVISIBLE (-5275 4400);
FORCEPROP 0 LAST CDS_SEC 1
J 0
(-5275 4400);
DISPLAY 1.021277 (-5275 4400);
DISPLAY INVISIBLE (-5275 4400);
FORCEPROP 1 LASTPIN (-5325 4425) $PN 1
J 0
(-5315 4405);
DISPLAY 0.489362 (-5315 4405);
PAINT MONO (-5315 4405);
FORCEPROP 1 LASTPIN (-5325 4225) $PN 2
J 0
(-5315 4205);
DISPLAY 0.489362 (-5315 4205);
PAINT MONO (-5315 4205);
FORCEPROP 1 LAST MATERIAL X7R
J 0
(-5275 4275);
DISPLAY 0.489362 (-5275 4275);
PAINT SKYBLUE (-5275 4275);
FORCEPROP 1 LAST PACK_TYPE 0402
J 0
(-5275 4225);
DISPLAY 0.489362 (-5275 4225);
PAINT SKYBLUE (-5275 4225);
FORCEPROP 1 LAST VOLTAGE 50V
J 0
(-5275 4325);
DISPLAY 0.489362 (-5275 4325);
PAINT SKYBLUE (-5275 4325);
FORCEPROP 1 LAST TOLERANCE 10%
J 0
(-5275 4300);
DISPLAY 0.489362 (-5275 4300);
PAINT SKYBLUE (-5275 4300);
FORCEPROP 1 LAST VALUE 3300PF
J 0
(-5275 4350);
DISPLAY 0.489362 (-5275 4350);
PAINT SKYBLUE (-5275 4350);
FORCEPROP 2 LAST CDS_LIB pure_quanta
J 0
(-5325 4325);
DISPLAY INVISIBLE (-5325 4325);
FORCEPROP 1 LAST PATH I62
J 0
(-5275 4475);
DISPLAY 0.978723 (-5275 4475);
PAINT WHITE (-5275 4475);
DISPLAY INVISIBLE (-5275 4475);
FORCEPROP 1 LAST PART_NUMBER TMP_QCH2336K1B12
J 0
(-5275 4250);
DISPLAY 0.489362 (-5275 4250);
PAINT SKYBLUE (-5275 4250);
DISPLAY INVISIBLE (-5275 4250);
FORCEADD UNIVERSAL_GND..1
(-7625 5175);
FORCEPROP 3 LASTPIN (-7625 5225) SIG_NAME GND\g
J 0
(-7615 5235);
DISPLAY 0.659574 (-7615 5235);
PAINT MONO (-7615 5235);
DISPLAY INVISIBLE (-7615 5235);
FORCEPROP 2 LAST CDS_LIB pure_quanta_power
J 0
(-7625 5175);
DISPLAY INVISIBLE (-7625 5175);
FORCEPROP 1 LAST HDL_POWER GND
J 1
(-7600 5100);
DISPLAY 0.872340 (-7600 5100);
PAINT GREEN (-7600 5100);
DISPLAY INVISIBLE (-7600 5100);
FORCEPROP 1 LAST PATH I63
J 0
(-7550 5175);
DISPLAY 0.872340 (-7550 5175);
PAINT AQUA (-7550 5175);
DISPLAY INVISIBLE (-7550 5175);
FORCEADD Q_CAP..1
(-7625 5425);
FORCEPROP 1 LAST LOCATION C298
J 0
(-7575 5525);
DISPLAY 0.489362 (-7575 5525);
PAINT SKYBLUE (-7575 5525);
FORCEPROP 0 LAST $SEC 1
J 0
(-7575 5550);
DISPLAY 0.680851 (-7575 5550);
PAINT MONO (-7575 5550);
DISPLAY INVISIBLE (-7575 5550);
FORCEPROP 0 LAST CDS_SEC 1
J 0
(-7575 5550);
DISPLAY 1.021277 (-7575 5550);
DISPLAY INVISIBLE (-7575 5550);
FORCEPROP 1 LASTPIN (-7625 5525) $PN 1
J 0
(-7615 5505);
DISPLAY 0.489362 (-7615 5505);
PAINT MONO (-7615 5505);
FORCEPROP 1 LASTPIN (-7625 5325) $PN 2
J 0
(-7615 5305);
DISPLAY 0.489362 (-7615 5305);
PAINT MONO (-7615 5305);
FORCEPROP 1 LAST VALUE 10PF
J 0
(-7575 5475);
DISPLAY 0.489362 (-7575 5475);
PAINT SKYBLUE (-7575 5475);
FORCEPROP 1 LAST PACK_TYPE 0402
J 0
(-7575 5225);
DISPLAY 0.489362 (-7575 5225);
PAINT SKYBLUE (-7575 5225);
FORCEPROP 1 LAST MATERIAL EMPTY
J 0
(-7575 5325);
DISPLAY 0.489362 (-7575 5325);
PAINT RED (-7575 5325);
FORCEPROP 1 LAST TOLERANCE 5%
J 0
(-7575 5375);
DISPLAY 0.489362 (-7575 5375);
PAINT SKYBLUE (-7575 5375);
FORCEPROP 1 LAST VOLTAGE 50V
J 0
(-7575 5425);
DISPLAY 0.489362 (-7575 5425);
PAINT SKYBLUE (-7575 5425);
FORCEPROP 2 LAST CDS_LIB pure_quanta
J 0
(-7625 5425);
DISPLAY INVISIBLE (-7625 5425);
FORCEPROP 1 LAST PATH I64
J 0
(-7575 5575);
DISPLAY 0.978723 (-7575 5575);
PAINT WHITE (-7575 5575);
DISPLAY INVISIBLE (-7575 5575);
FORCEPROP 1 LAST PART_NUMBER CH01006JB08
J 0
(-7575 5275);
DISPLAY 0.489362 (-7575 5275);
PAINT SKYBLUE (-7575 5275);
DISPLAY INVISIBLE (-7575 5275);
FORCEADD UNIVERSAL_GND..1
(-7400 5175);
FORCEPROP 3 LASTPIN (-7400 5225) SIG_NAME GND\g
J 0
(-7390 5235);
DISPLAY 0.659574 (-7390 5235);
PAINT MONO (-7390 5235);
DISPLAY INVISIBLE (-7390 5235);
FORCEPROP 2 LAST CDS_LIB pure_quanta_power
J 0
(-7400 5175);
DISPLAY INVISIBLE (-7400 5175);
FORCEPROP 1 LAST HDL_POWER GND
J 1
(-7375 5100);
DISPLAY 0.872340 (-7375 5100);
PAINT GREEN (-7375 5100);
DISPLAY INVISIBLE (-7375 5100);
FORCEPROP 1 LAST PATH I65
J 0
(-7325 5175);
DISPLAY 0.872340 (-7325 5175);
PAINT AQUA (-7325 5175);
DISPLAY INVISIBLE (-7325 5175);
FORCEADD Q_CAP..1
(-7400 5425);
FORCEPROP 1 LAST LOCATION C299
J 0
(-7350 5525);
DISPLAY 0.489362 (-7350 5525);
PAINT SKYBLUE (-7350 5525);
FORCEPROP 0 LAST $SEC 1
J 0
(-7350 5550);
DISPLAY 0.680851 (-7350 5550);
PAINT MONO (-7350 5550);
DISPLAY INVISIBLE (-7350 5550);
FORCEPROP 0 LAST CDS_SEC 1
J 0
(-7350 5550);
DISPLAY 1.021277 (-7350 5550);
DISPLAY INVISIBLE (-7350 5550);
FORCEPROP 1 LASTPIN (-7400 5525) $PN 1
J 0
(-7390 5505);
DISPLAY 0.489362 (-7390 5505);
PAINT MONO (-7390 5505);
FORCEPROP 1 LASTPIN (-7400 5325) $PN 2
J 0
(-7390 5305);
DISPLAY 0.489362 (-7390 5305);
PAINT MONO (-7390 5305);
FORCEPROP 1 LAST MATERIAL EMPTY
J 0
(-7350 5325);
DISPLAY 0.489362 (-7350 5325);
PAINT RED (-7350 5325);
FORCEPROP 1 LAST TOLERANCE 5%
J 0
(-7350 5375);
DISPLAY 0.489362 (-7350 5375);
PAINT SKYBLUE (-7350 5375);
FORCEPROP 1 LAST PACK_TYPE 0402
J 0
(-7350 5225);
DISPLAY 0.489362 (-7350 5225);
PAINT SKYBLUE (-7350 5225);
FORCEPROP 1 LAST VOLTAGE 50V
J 0
(-7350 5425);
DISPLAY 0.489362 (-7350 5425);
PAINT SKYBLUE (-7350 5425);
FORCEPROP 1 LAST VALUE 10PF
J 0
(-7350 5475);
DISPLAY 0.489362 (-7350 5475);
PAINT SKYBLUE (-7350 5475);
FORCEPROP 2 LAST CDS_LIB pure_quanta
J 0
(-7400 5425);
DISPLAY INVISIBLE (-7400 5425);
FORCEPROP 1 LAST PATH I66
J 0
(-7350 5575);
DISPLAY 0.978723 (-7350 5575);
PAINT WHITE (-7350 5575);
DISPLAY INVISIBLE (-7350 5575);
FORCEPROP 1 LAST PART_NUMBER CH01006JB08
J 0
(-7350 5275);
DISPLAY 0.489362 (-7350 5275);
PAINT SKYBLUE (-7350 5275);
DISPLAY INVISIBLE (-7350 5275);
FORCEADD UNIVERSAL_GND..1
(-7175 5175);
FORCEPROP 3 LASTPIN (-7175 5225) SIG_NAME GND\g
J 0
(-7165 5235);
DISPLAY 0.659574 (-7165 5235);
PAINT MONO (-7165 5235);
DISPLAY INVISIBLE (-7165 5235);
FORCEPROP 2 LAST CDS_LIB pure_quanta_power
J 0
(-7175 5175);
DISPLAY INVISIBLE (-7175 5175);
FORCEPROP 1 LAST HDL_POWER GND
J 1
(-7150 5100);
DISPLAY 0.872340 (-7150 5100);
PAINT GREEN (-7150 5100);
DISPLAY INVISIBLE (-7150 5100);
FORCEPROP 1 LAST PATH I67
J 0
(-7100 5175);
DISPLAY 0.872340 (-7100 5175);
PAINT AQUA (-7100 5175);
DISPLAY INVISIBLE (-7100 5175);
FORCEADD Q_CAP..1
(-7175 5425);
FORCEPROP 1 LAST LOCATION C302
J 0
(-7125 5525);
DISPLAY 0.489362 (-7125 5525);
PAINT SKYBLUE (-7125 5525);
FORCEPROP 0 LAST $SEC 1
J 0
(-7125 5550);
DISPLAY 0.680851 (-7125 5550);
PAINT MONO (-7125 5550);
DISPLAY INVISIBLE (-7125 5550);
FORCEPROP 0 LAST CDS_SEC 1
J 0
(-7125 5550);
DISPLAY 1.021277 (-7125 5550);
DISPLAY INVISIBLE (-7125 5550);
FORCEPROP 1 LASTPIN (-7175 5525) $PN 1
J 0
(-7165 5505);
DISPLAY 0.489362 (-7165 5505);
PAINT MONO (-7165 5505);
FORCEPROP 1 LASTPIN (-7175 5325) $PN 2
J 0
(-7165 5305);
DISPLAY 0.489362 (-7165 5305);
PAINT MONO (-7165 5305);
FORCEPROP 1 LAST MATERIAL EMPTY
J 0
(-7125 5325);
DISPLAY 0.489362 (-7125 5325);
PAINT RED (-7125 5325);
FORCEPROP 1 LAST VALUE 10PF
J 0
(-7125 5475);
DISPLAY 0.489362 (-7125 5475);
PAINT SKYBLUE (-7125 5475);
FORCEPROP 1 LAST VOLTAGE 50V
J 0
(-7125 5425);
DISPLAY 0.489362 (-7125 5425);
PAINT SKYBLUE (-7125 5425);
FORCEPROP 1 LAST TOLERANCE 5%
J 0
(-7125 5375);
DISPLAY 0.489362 (-7125 5375);
PAINT SKYBLUE (-7125 5375);
FORCEPROP 1 LAST PACK_TYPE 0402
J 0
(-7125 5225);
DISPLAY 0.489362 (-7125 5225);
PAINT SKYBLUE (-7125 5225);
FORCEPROP 2 LAST CDS_LIB pure_quanta
J 0
(-7175 5425);
DISPLAY INVISIBLE (-7175 5425);
FORCEPROP 1 LAST PATH I68
J 0
(-7125 5575);
DISPLAY 0.978723 (-7125 5575);
PAINT WHITE (-7125 5575);
DISPLAY INVISIBLE (-7125 5575);
FORCEPROP 1 LAST PART_NUMBER CH01006JB08
J 0
(-7125 5275);
DISPLAY 0.489362 (-7125 5275);
PAINT SKYBLUE (-7125 5275);
DISPLAY INVISIBLE (-7125 5275);
FORCEADD Q_RES..2
(-7550 6375);
FORCEPROP 1 LAST LOCATION R8287
J 0
(-7500 6500);
DISPLAY 0.489362 (-7500 6500);
PAINT SKYBLUE (-7500 6500);
FORCEPROP 0 LAST $SEC 1
J 0
(-7500 6525);
DISPLAY 0.680851 (-7500 6525);
PAINT MONO (-7500 6525);
DISPLAY INVISIBLE (-7500 6525);
FORCEPROP 0 LAST CDS_SEC 1
J 0
(-7500 6525);
DISPLAY 1.021277 (-7500 6525);
DISPLAY INVISIBLE (-7500 6525);
FORCEPROP 1 LASTPIN (-7550 6475) $PN 1
J 0
(-7545 6437);
DISPLAY 0.489362 (-7545 6437);
PAINT MONO (-7545 6437);
FORCEPROP 1 LASTPIN (-7550 6275) $PN 2
J 0
(-7545 6285);
DISPLAY 0.489362 (-7545 6285);
PAINT MONO (-7545 6285);
FORCEPROP 1 LAST WATTAGE 1/16W
J 0
(-7500 6350);
DISPLAY 0.489362 (-7500 6350);
PAINT SKYBLUE (-7500 6350);
FORCEPROP 1 LAST VALUE 1K
J 0
(-7500 6450);
DISPLAY 0.489362 (-7500 6450);
PAINT SKYBLUE (-7500 6450);
FORCEPROP 1 LAST TOLERANCE 1%
J 0
(-7500 6400);
DISPLAY 0.489362 (-7500 6400);
PAINT SKYBLUE (-7500 6400);
FORCEPROP 1 LAST MATERIAL EMPTY
J 0
(-7500 6300);
DISPLAY 0.489362 (-7500 6300);
PAINT RED (-7500 6300);
FORCEPROP 1 LAST PACK_TYPE 0402LF
J 0
(-7500 6250);
DISPLAY 0.489362 (-7500 6250);
PAINT SKYBLUE (-7500 6250);
FORCEPROP 2 LAST CDS_LIB pure_quanta
J 0
(-7550 6375);
DISPLAY INVISIBLE (-7550 6375);
FORCEPROP 1 LAST PATH I69
J 0
(-7500 6550);
DISPLAY 0.978723 (-7500 6550);
PAINT WHITE (-7500 6550);
DISPLAY INVISIBLE (-7500 6550);
FORCEPROP 1 LAST PART_NUMBER CS21002FB06
J 0
(-7510 6250);
DISPLAY 0.489362 (-7510 6250);
PAINT SKYBLUE (-7510 6250);
DISPLAY INVISIBLE (-7510 6250);
FORCEADD OFFPAGE..2
R 2
(-8425 5750);
FORCEPROP 2 LAST $XR0 27 
J 0
(-8649 5750);
DISPLAY 0.638298 (-8649 5750);
PAINT MONO (-8649 5750);
FORCEPROP 2 LAST CDS_LIB standard
J 0
(-8425 5750);
DISPLAY INVISIBLE (-8425 5750);
FORCEPROP 1 LAST OFFPAGE TRUE
J 2
(-8750 5625);
DISPLAY 0.872340 (-8750 5625);
PAINT GREEN (-8750 5625);
DISPLAY INVISIBLE (-8750 5625);
FORCEPROP 1 LAST COMMENT_BODY TRUE
J 2
(-8380 5655);
DISPLAY 0.872340 (-8380 5655);
PAINT GREEN (-8380 5655);
DISPLAY INVISIBLE (-8380 5655);
FORCEPROP 2 LAST PATH I7
J 0
(-8675 5800);
DISPLAY 0.680851 (-8675 5800);
DISPLAY INVISIBLE (-8675 5800);
FORCEADD Q_RES..2
(-7250 6375);
FORCEPROP 1 LAST LOCATION R8289
J 0
(-7200 6500);
DISPLAY 0.489362 (-7200 6500);
PAINT SKYBLUE (-7200 6500);
FORCEPROP 0 LAST $SEC 1
J 0
(-7200 6525);
DISPLAY 0.680851 (-7200 6525);
PAINT MONO (-7200 6525);
DISPLAY INVISIBLE (-7200 6525);
FORCEPROP 0 LAST CDS_SEC 1
J 0
(-7200 6525);
DISPLAY 1.021277 (-7200 6525);
DISPLAY INVISIBLE (-7200 6525);
FORCEPROP 1 LASTPIN (-7250 6475) $PN 1
J 0
(-7245 6437);
DISPLAY 0.489362 (-7245 6437);
PAINT MONO (-7245 6437);
FORCEPROP 1 LASTPIN (-7250 6275) $PN 2
J 0
(-7245 6285);
DISPLAY 0.489362 (-7245 6285);
PAINT MONO (-7245 6285);
FORCEPROP 1 LAST TOLERANCE 1%
J 0
(-7200 6400);
DISPLAY 0.489362 (-7200 6400);
PAINT SKYBLUE (-7200 6400);
FORCEPROP 1 LAST VALUE 1K
J 0
(-7200 6450);
DISPLAY 0.489362 (-7200 6450);
PAINT SKYBLUE (-7200 6450);
FORCEPROP 1 LAST WATTAGE 1/16W
J 0
(-7200 6350);
DISPLAY 0.489362 (-7200 6350);
PAINT SKYBLUE (-7200 6350);
FORCEPROP 1 LAST PACK_TYPE 0402LF
J 0
(-7200 6250);
DISPLAY 0.489362 (-7200 6250);
PAINT SKYBLUE (-7200 6250);
FORCEPROP 1 LAST MATERIAL EMPTY
J 0
(-7200 6300);
DISPLAY 0.489362 (-7200 6300);
PAINT RED (-7200 6300);
FORCEPROP 2 LAST CDS_LIB pure_quanta
J 0
(-7250 6375);
DISPLAY INVISIBLE (-7250 6375);
FORCEPROP 1 LAST PATH I70
J 0
(-7200 6550);
DISPLAY 0.978723 (-7200 6550);
PAINT WHITE (-7200 6550);
DISPLAY INVISIBLE (-7200 6550);
FORCEPROP 1 LAST PART_NUMBER CS21002FB06
J 0
(-7210 6250);
DISPLAY 0.489362 (-7210 6250);
PAINT SKYBLUE (-7210 6250);
DISPLAY INVISIBLE (-7210 6250);
FORCEADD Q_RES..2
(-6975 6375);
FORCEPROP 1 LAST LOCATION R8293
J 0
(-6925 6500);
DISPLAY 0.489362 (-6925 6500);
PAINT SKYBLUE (-6925 6500);
FORCEPROP 0 LAST $SEC 1
J 0
(-6925 6525);
DISPLAY 0.680851 (-6925 6525);
PAINT MONO (-6925 6525);
DISPLAY INVISIBLE (-6925 6525);
FORCEPROP 0 LAST CDS_SEC 1
J 0
(-6925 6525);
DISPLAY 1.021277 (-6925 6525);
DISPLAY INVISIBLE (-6925 6525);
FORCEPROP 1 LASTPIN (-6975 6475) $PN 1
J 0
(-6970 6437);
DISPLAY 0.489362 (-6970 6437);
PAINT MONO (-6970 6437);
FORCEPROP 1 LASTPIN (-6975 6275) $PN 2
J 0
(-6970 6285);
DISPLAY 0.489362 (-6970 6285);
PAINT MONO (-6970 6285);
FORCEPROP 1 LAST WATTAGE 1/16W
J 0
(-6925 6350);
DISPLAY 0.489362 (-6925 6350);
PAINT SKYBLUE (-6925 6350);
FORCEPROP 1 LAST PACK_TYPE 0402LF
J 0
(-6925 6200);
DISPLAY 0.489362 (-6925 6200);
PAINT SKYBLUE (-6925 6200);
FORCEPROP 1 LAST TOLERANCE 1%
J 0
(-6925 6400);
DISPLAY 0.489362 (-6925 6400);
PAINT SKYBLUE (-6925 6400);
FORCEPROP 1 LAST MATERIAL EMPTY
J 0
(-6925 6300);
DISPLAY 0.489362 (-6925 6300);
PAINT RED (-6925 6300);
FORCEPROP 1 LAST VALUE 1K
J 0
(-6925 6450);
DISPLAY 0.489362 (-6925 6450);
PAINT SKYBLUE (-6925 6450);
FORCEPROP 2 LAST CDS_LIB pure_quanta
J 0
(-6975 6375);
DISPLAY INVISIBLE (-6975 6375);
FORCEPROP 1 LAST PATH I71
J 0
(-6925 6550);
DISPLAY 0.978723 (-6925 6550);
PAINT WHITE (-6925 6550);
DISPLAY INVISIBLE (-6925 6550);
FORCEPROP 1 LAST PART_NUMBER CS21002FB06
J 0
(-6925 6250);
DISPLAY 0.489362 (-6925 6250);
PAINT SKYBLUE (-6925 6250);
DISPLAY INVISIBLE (-6925 6250);
FORCEADD Q_RES..2
(-6625 4650);
FORCEPROP 1 LAST LOCATION PR294
J 0
(-6575 4775);
DISPLAY 0.489362 (-6575 4775);
PAINT SKYBLUE (-6575 4775);
FORCEPROP 0 LAST $SEC 1
J 0
(-6575 4800);
DISPLAY 0.680851 (-6575 4800);
PAINT MONO (-6575 4800);
DISPLAY INVISIBLE (-6575 4800);
FORCEPROP 0 LAST CDS_SEC 1
J 0
(-6575 4800);
DISPLAY 1.021277 (-6575 4800);
DISPLAY INVISIBLE (-6575 4800);
FORCEPROP 1 LASTPIN (-6625 4750) $PN 1
J 0
(-6620 4712);
DISPLAY 0.489362 (-6620 4712);
PAINT MONO (-6620 4712);
FORCEPROP 1 LASTPIN (-6625 4550) $PN 2
J 0
(-6620 4560);
DISPLAY 0.489362 (-6620 4560);
PAINT MONO (-6620 4560);
FORCEPROP 1 LAST WATTAGE 1/16W
J 0
(-6575 4625);
DISPLAY 0.489362 (-6575 4625);
PAINT SKYBLUE (-6575 4625);
FORCEPROP 1 LAST VALUE 49.9
J 0
(-6575 4725);
DISPLAY 0.489362 (-6575 4725);
PAINT SKYBLUE (-6575 4725);
FORCEPROP 1 LAST MATERIAL CHIP
J 0
(-6575 4575);
DISPLAY 0.489362 (-6575 4575);
PAINT SKYBLUE (-6575 4575);
FORCEPROP 1 LAST PACK_TYPE 0402LF
J 0
(-6575 4475);
DISPLAY 0.489362 (-6575 4475);
PAINT SKYBLUE (-6575 4475);
FORCEPROP 1 LAST TOLERANCE 1%
J 0
(-6575 4675);
DISPLAY 0.489362 (-6575 4675);
PAINT SKYBLUE (-6575 4675);
FORCEPROP 2 LAST CDS_LIB pure_quanta
J 0
(-6625 4650);
DISPLAY INVISIBLE (-6625 4650);
FORCEPROP 1 LAST PATH I72
J 0
(-6575 4825);
DISPLAY 0.978723 (-6575 4825);
PAINT WHITE (-6575 4825);
DISPLAY INVISIBLE (-6575 4825);
FORCEPROP 1 LAST PART_NUMBER CS04992FB07
J 0
(-6575 4525);
DISPLAY 0.489362 (-6575 4525);
PAINT SKYBLUE (-6575 4525);
DISPLAY INVISIBLE (-6575 4525);
FORCEADD VCC_CORE..1
(-6625 4850);
FORCEPROP 3 LASTPIN (-6625 4800) SIG_NAME PVDDCR_CPU0_P0\g
J 0
(-6615 4810);
DISPLAY 0.659574 (-6615 4810);
PAINT MONO (-6615 4810);
DISPLAY INVISIBLE (-6615 4810);
FORCEPROP 1 LAST HDL_POWER PVDDCR_CPU0_P0
J 1
(-6625 4900);
DISPLAY 0.489362 (-6625 4900);
PAINT GREEN (-6625 4900);
FORCEPROP 2 LAST CDS_LIB pure_quanta_power
J 0
(-6625 4850);
DISPLAY INVISIBLE (-6625 4850);
FORCEPROP 1 LAST PATH I73
J 0
(-6575 4875);
DISPLAY 0.872340 (-6575 4875);
PAINT AQUA (-6575 4875);
DISPLAY INVISIBLE (-6575 4875);
FORCEADD OFFPAGE..2
R 2
(-6375 5050);
FORCEPROP 2 LAST $XR1 81 
J 0
(-6689 5050);
DISPLAY 0.638298 (-6689 5050);
PAINT MONO (-6689 5050);
FORCEPROP 2 LAST $XR0 83 
J 0
(-6599 5050);
DISPLAY 0.638298 (-6599 5050);
PAINT MONO (-6599 5050);
FORCEPROP 2 LAST CDS_LIB standard
J 0
(-6375 5050);
DISPLAY INVISIBLE (-6375 5050);
FORCEPROP 1 LAST OFFPAGE TRUE
J 2
(-6700 4925);
DISPLAY 0.872340 (-6700 4925);
PAINT GREEN (-6700 4925);
DISPLAY INVISIBLE (-6700 4925);
FORCEPROP 1 LAST COMMENT_BODY TRUE
J 2
(-6330 4955);
DISPLAY 0.872340 (-6330 4955);
PAINT GREEN (-6330 4955);
DISPLAY INVISIBLE (-6330 4955);
FORCEPROP 2 LAST PATH I74
J 0
(-6575 5100);
DISPLAY 0.680851 (-6575 5100);
DISPLAY INVISIBLE (-6575 5100);
FORCEADD OFFPAGE..3
R 2
(-6325 5200);
FORCEPROP 2 LAST $XR0 151 
J 0
(-6605 5200);
DISPLAY 0.638298 (-6605 5200);
PAINT MONO (-6605 5200);
FORCEPROP 2 LAST $XR1 193 
J 0
(-6725 5200);
DISPLAY 0.638298 (-6725 5200);
PAINT MONO (-6725 5200);
FORCEPROP 2 LAST CDS_LIB standard
J 0
(-6325 5200);
DISPLAY INVISIBLE (-6325 5200);
FORCEPROP 1 LAST OFFPAGE TRUE
J 2
(-6650 5075);
DISPLAY 0.872340 (-6650 5075);
PAINT GREEN (-6650 5075);
DISPLAY INVISIBLE (-6650 5075);
FORCEPROP 1 LAST COMMENT_BODY TRUE
J 2
(-6275 5100);
DISPLAY 0.872340 (-6275 5100);
PAINT GREEN (-6275 5100);
DISPLAY INVISIBLE (-6275 5100);
FORCEPROP 2 LAST PATH I75
J 0
(-6600 5250);
DISPLAY 0.680851 (-6600 5250);
DISPLAY INVISIBLE (-6600 5250);
FORCEADD OFFPAGE..4
R 2
(-6325 5350);
FORCEPROP 2 LAST $XR1 193 
J 0
(-6697 5350);
DISPLAY 0.638298 (-6697 5350);
PAINT MONO (-6697 5350);
FORCEPROP 2 LAST $XR0 151 
J 0
(-6577 5350);
DISPLAY 0.638298 (-6577 5350);
PAINT MONO (-6577 5350);
FORCEPROP 2 LAST CDS_LIB standard
J 0
(-6325 5350);
DISPLAY INVISIBLE (-6325 5350);
FORCEPROP 1 LAST OFFPAGE TRUE
J 2
(-6650 5225);
DISPLAY 0.872340 (-6650 5225);
PAINT GREEN (-6650 5225);
DISPLAY INVISIBLE (-6650 5225);
FORCEPROP 1 LAST COMMENT_BODY TRUE
J 2
(-6300 5250);
DISPLAY 0.872340 (-6300 5250);
PAINT GREEN (-6300 5250);
DISPLAY INVISIBLE (-6300 5250);
FORCEPROP 2 LAST PATH I76
J 0
(-6575 5400);
DISPLAY 0.680851 (-6575 5400);
DISPLAY INVISIBLE (-6575 5400);
FORCEADD OFFPAGE..2
R 2
(-6200 6500);
FORCEPROP 2 LAST $XR0 82 
J 0
(-6454 6500);
DISPLAY 0.638298 (-6454 6500);
PAINT MONO (-6454 6500);
FORCEPROP 2 LAST CDS_LIB standard
J 2
(-6200 6500);
DISPLAY INVISIBLE (-6200 6500);
FORCEPROP 1 LAST OFFPAGE TRUE
J 2
(-6525 6375);
DISPLAY 0.872340 (-6525 6375);
PAINT GREEN (-6525 6375);
DISPLAY INVISIBLE (-6525 6375);
FORCEPROP 1 LAST COMMENT_BODY TRUE
J 2
(-6155 6405);
DISPLAY 0.872340 (-6155 6405);
PAINT GREEN (-6155 6405);
DISPLAY INVISIBLE (-6155 6405);
FORCEPROP 2 LAST PATH I79
J 0
(-6450 6550);
DISPLAY 0.680851 (-6450 6550);
DISPLAY INVISIBLE (-6450 6550);
FORCEADD OFFPAGE..4
R 2
(-8425 5900);
FORCEPROP 2 LAST $XR0 27 
J 0
(-8676 5900);
DISPLAY 0.638298 (-8676 5900);
PAINT MONO (-8676 5900);
FORCEPROP 2 LAST CDS_LIB standard
J 0
(-8425 5900);
DISPLAY INVISIBLE (-8425 5900);
FORCEPROP 1 LAST OFFPAGE TRUE
J 2
(-8750 5775);
DISPLAY 0.872340 (-8750 5775);
PAINT GREEN (-8750 5775);
DISPLAY INVISIBLE (-8750 5775);
FORCEPROP 1 LAST COMMENT_BODY TRUE
J 2
(-8400 5800);
DISPLAY 0.872340 (-8400 5800);
PAINT GREEN (-8400 5800);
DISPLAY INVISIBLE (-8400 5800);
FORCEPROP 2 LAST PATH I8
J 0
(-8625 5950);
DISPLAY 0.680851 (-8625 5950);
DISPLAY INVISIBLE (-8625 5950);
FORCEADD OFFPAGE..4
R 2
(-6200 6350);
FORCEPROP 2 LAST $XR0 80 
J 0
(-6421 6350);
DISPLAY 0.638298 (-6421 6350);
PAINT MONO (-6421 6350);
FORCEPROP 2 LAST CDS_LIB standard
J 0
(-6200 6350);
DISPLAY INVISIBLE (-6200 6350);
FORCEPROP 1 LAST OFFPAGE TRUE
J 2
(-6525 6225);
DISPLAY 0.872340 (-6525 6225);
PAINT GREEN (-6525 6225);
DISPLAY INVISIBLE (-6525 6225);
FORCEPROP 1 LAST COMMENT_BODY TRUE
J 2
(-6175 6250);
DISPLAY 0.872340 (-6175 6250);
PAINT GREEN (-6175 6250);
DISPLAY INVISIBLE (-6175 6250);
FORCEPROP 2 LAST PATH I80
J 0
(-6400 6400);
DISPLAY 0.680851 (-6400 6400);
DISPLAY INVISIBLE (-6400 6400);
FORCEADD VCC_CORE..1
(-6100 6900);
FORCEPROP 3 LASTPIN (-6100 6850) SIG_NAME P3V3_AUX\g
J 0
(-6090 6860);
DISPLAY 0.659574 (-6090 6860);
PAINT MONO (-6090 6860);
DISPLAY INVISIBLE (-6090 6860);
FORCEPROP 1 LAST HDL_POWER P3V3_AUX
J 1
(-6100 6950);
DISPLAY 0.489362 (-6100 6950);
PAINT GREEN (-6100 6950);
FORCEPROP 2 LAST CDS_LIB pure_quanta_power
J 0
(-6100 6900);
DISPLAY INVISIBLE (-6100 6900);
FORCEPROP 1 LAST PATH I81
J 0
(-6050 6925);
DISPLAY 0.872340 (-6050 6925);
PAINT AQUA (-6050 6925);
DISPLAY INVISIBLE (-6050 6925);
FORCEADD Q_RES..1
(-5700 6775);
FORCEPROP 1 LAST LOCATION R8300
J 0
(-5750 6825);
DISPLAY 0.489362 (-5750 6825);
PAINT SKYBLUE (-5750 6825);
FORCEPROP 0 LAST $SEC 1
J 0
(-5750 6850);
DISPLAY 0.680851 (-5750 6850);
PAINT MONO (-5750 6850);
DISPLAY INVISIBLE (-5750 6850);
FORCEPROP 0 LAST CDS_SEC 1
J 0
(-5750 6850);
DISPLAY 1.021277 (-5750 6850);
DISPLAY INVISIBLE (-5750 6850);
FORCEPROP 1 LASTPIN (-5800 6775) $PN 1
J 0
(-5788 6787);
DISPLAY 0.489362 (-5788 6787);
PAINT MONO (-5788 6787);
FORCEPROP 1 LASTPIN (-5600 6775) $PN 2
J 0
(-5638 6787);
DISPLAY 0.489362 (-5638 6787);
PAINT MONO (-5638 6787);
FORCEPROP 1 LAST MATERIAL CHIP
J 0
(-6025 6675);
DISPLAY 0.489362 (-6025 6675);
PAINT SKYBLUE (-6025 6675);
FORCEPROP 1 LAST PACK_TYPE 0402LF
J 0
(-5600 6675);
DISPLAY 0.489362 (-5600 6675);
PAINT SKYBLUE (-5600 6675);
FORCEPROP 1 LAST TOLERANCE 1%
J 0
(-5575 6800);
DISPLAY 0.489362 (-5575 6800);
PAINT SKYBLUE (-5575 6800);
FORCEPROP 1 LAST VALUE 1K
J 2
(-5850 6800);
DISPLAY 0.489362 (-5850 6800);
PAINT SKYBLUE (-5850 6800);
FORCEPROP 1 LAST WATTAGE 1/16W
J 0
(-5600 6725);
DISPLAY 0.489362 (-5600 6725);
PAINT SKYBLUE (-5600 6725);
FORCEPROP 2 LAST CDS_LIB pure_quanta
J 0
(-5700 6775);
DISPLAY INVISIBLE (-5700 6775);
FORCEPROP 1 LAST PATH I82
J 0
(-5750 6925);
DISPLAY 0.978723 (-5750 6925);
PAINT WHITE (-5750 6925);
DISPLAY INVISIBLE (-5750 6925);
FORCEPROP 1 LAST PART_NUMBER CS21002FB06
J 0
(-6025 6725);
DISPLAY 0.489362 (-6025 6725);
PAINT SKYBLUE (-6025 6725);
DISPLAY INVISIBLE (-6025 6725);
FORCEADD Q_RES..1
(-5500 5050);
FORCEPROP 1 LAST LOCATION R8310
J 0
(-5550 5100);
DISPLAY 0.489362 (-5550 5100);
PAINT SKYBLUE (-5550 5100);
FORCEPROP 0 LAST $SEC 1
J 0
(-5550 5125);
DISPLAY 0.680851 (-5550 5125);
PAINT MONO (-5550 5125);
DISPLAY INVISIBLE (-5550 5125);
FORCEPROP 0 LAST CDS_SEC 1
J 0
(-5550 5125);
DISPLAY 1.021277 (-5550 5125);
DISPLAY INVISIBLE (-5550 5125);
FORCEPROP 1 LASTPIN (-5600 5050) $PN 1
J 0
(-5588 5062);
DISPLAY 0.489362 (-5588 5062);
PAINT MONO (-5588 5062);
FORCEPROP 1 LASTPIN (-5400 5050) $PN 2
J 0
(-5438 5062);
DISPLAY 0.489362 (-5438 5062);
PAINT MONO (-5438 5062);
FORCEPROP 1 LAST PACK_TYPE 0402LF
J 0
(-5400 4975);
DISPLAY 0.489362 (-5400 4975);
PAINT SKYBLUE (-5400 4975);
FORCEPROP 1 LAST WATTAGE 1/16W
J 0
(-5400 5000);
DISPLAY 0.489362 (-5400 5000);
PAINT SKYBLUE (-5400 5000);
FORCEPROP 1 LAST VALUE 33
J 2
(-5625 5075);
DISPLAY 0.489362 (-5625 5075);
PAINT SKYBLUE (-5625 5075);
FORCEPROP 1 LAST MATERIAL CHIP
J 0
(-5750 4975);
DISPLAY 0.489362 (-5750 4975);
PAINT SKYBLUE (-5750 4975);
FORCEPROP 1 LAST TOLERANCE 5%
J 0
(-5375 5075);
DISPLAY 0.489362 (-5375 5075);
PAINT SKYBLUE (-5375 5075);
FORCEPROP 2 LAST CDS_LIB pure_quanta
J 0
(-5500 5050);
DISPLAY INVISIBLE (-5500 5050);
FORCEPROP 1 LAST PATH I83
J 0
(-5550 5200);
DISPLAY 0.978723 (-5550 5200);
PAINT WHITE (-5550 5200);
DISPLAY INVISIBLE (-5550 5200);
FORCEPROP 1 LAST PART_NUMBER CS03302JB10
J 0
(-5750 5000);
DISPLAY 0.489362 (-5750 5000);
PAINT SKYBLUE (-5750 5000);
DISPLAY INVISIBLE (-5750 5000);
FORCEADD Q_RES..1
(-5500 5200);
FORCEPROP 1 LAST LOCATION R8309
J 0
(-5550 5250);
DISPLAY 0.489362 (-5550 5250);
PAINT SKYBLUE (-5550 5250);
FORCEPROP 0 LAST $SEC 1
J 0
(-5550 5275);
DISPLAY 0.680851 (-5550 5275);
PAINT MONO (-5550 5275);
DISPLAY INVISIBLE (-5550 5275);
FORCEPROP 0 LAST CDS_SEC 1
J 0
(-5550 5275);
DISPLAY 1.021277 (-5550 5275);
DISPLAY INVISIBLE (-5550 5275);
FORCEPROP 1 LASTPIN (-5600 5200) $PN 1
J 0
(-5588 5212);
DISPLAY 0.489362 (-5588 5212);
PAINT MONO (-5588 5212);
FORCEPROP 1 LASTPIN (-5400 5200) $PN 2
J 0
(-5438 5212);
DISPLAY 0.489362 (-5438 5212);
PAINT MONO (-5438 5212);
FORCEPROP 1 LAST MATERIAL CHIP
J 0
(-5750 5125);
DISPLAY 0.489362 (-5750 5125);
PAINT SKYBLUE (-5750 5125);
FORCEPROP 1 LAST PACK_TYPE 0402LF
J 0
(-5400 5125);
DISPLAY 0.489362 (-5400 5125);
PAINT SKYBLUE (-5400 5125);
FORCEPROP 1 LAST VALUE 0
J 2
(-5625 5225);
DISPLAY 0.489362 (-5625 5225);
PAINT SKYBLUE (-5625 5225);
FORCEPROP 1 LAST TOLERANCE 5%
J 0
(-5375 5225);
DISPLAY 0.489362 (-5375 5225);
PAINT SKYBLUE (-5375 5225);
FORCEPROP 1 LAST WATTAGE 1/16W
J 0
(-5400 5150);
DISPLAY 0.489362 (-5400 5150);
PAINT SKYBLUE (-5400 5150);
FORCEPROP 2 LAST CDS_LIB pure_quanta
J 0
(-5500 5200);
DISPLAY INVISIBLE (-5500 5200);
FORCEPROP 1 LAST PATH I84
J 0
(-5550 5350);
DISPLAY 0.978723 (-5550 5350);
PAINT WHITE (-5550 5350);
DISPLAY INVISIBLE (-5550 5350);
FORCEPROP 1 LAST PART_NUMBER CS00002JB13
J 0
(-5750 5150);
DISPLAY 0.489362 (-5750 5150);
PAINT SKYBLUE (-5750 5150);
DISPLAY INVISIBLE (-5750 5150);
FORCEADD Q_RES..1
(-5500 5350);
FORCEPROP 1 LAST LOCATION R8308
J 0
(-5550 5400);
DISPLAY 0.489362 (-5550 5400);
PAINT SKYBLUE (-5550 5400);
FORCEPROP 0 LAST $SEC 1
J 0
(-5550 5425);
DISPLAY 0.680851 (-5550 5425);
PAINT MONO (-5550 5425);
DISPLAY INVISIBLE (-5550 5425);
FORCEPROP 0 LAST CDS_SEC 1
J 0
(-5550 5425);
DISPLAY 1.021277 (-5550 5425);
DISPLAY INVISIBLE (-5550 5425);
FORCEPROP 1 LASTPIN (-5600 5350) $PN 1
J 0
(-5588 5362);
DISPLAY 0.489362 (-5588 5362);
PAINT MONO (-5588 5362);
FORCEPROP 1 LASTPIN (-5400 5350) $PN 2
J 0
(-5438 5362);
DISPLAY 0.489362 (-5438 5362);
PAINT MONO (-5438 5362);
FORCEPROP 1 LAST MATERIAL CHIP
J 0
(-5750 5275);
DISPLAY 0.489362 (-5750 5275);
PAINT SKYBLUE (-5750 5275);
FORCEPROP 1 LAST VALUE 0
J 2
(-5625 5375);
DISPLAY 0.489362 (-5625 5375);
PAINT SKYBLUE (-5625 5375);
FORCEPROP 1 LAST PACK_TYPE 0402LF
J 0
(-5400 5275);
DISPLAY 0.489362 (-5400 5275);
PAINT SKYBLUE (-5400 5275);
FORCEPROP 1 LAST WATTAGE 1/16W
J 0
(-5400 5300);
DISPLAY 0.489362 (-5400 5300);
PAINT SKYBLUE (-5400 5300);
FORCEPROP 1 LAST TOLERANCE 5%
J 0
(-5375 5375);
DISPLAY 0.489362 (-5375 5375);
PAINT SKYBLUE (-5375 5375);
FORCEPROP 2 LAST CDS_LIB pure_quanta
J 0
(-5500 5350);
DISPLAY INVISIBLE (-5500 5350);
FORCEPROP 1 LAST PATH I85
J 0
(-5550 5500);
DISPLAY 0.978723 (-5550 5500);
PAINT WHITE (-5550 5500);
DISPLAY INVISIBLE (-5550 5500);
FORCEPROP 1 LAST PART_NUMBER CS00002JB13
J 0
(-5750 5300);
DISPLAY 0.489362 (-5750 5300);
PAINT SKYBLUE (-5750 5300);
DISPLAY INVISIBLE (-5750 5300);
FORCEADD Q_RES..1
(-5600 5600);
FORCEPROP 1 LAST LOCATION PR305
J 0
(-5650 5650);
DISPLAY 0.489362 (-5650 5650);
PAINT SKYBLUE (-5650 5650);
FORCEPROP 0 LAST $SEC 1
J 0
(-5650 5675);
DISPLAY 0.680851 (-5650 5675);
PAINT MONO (-5650 5675);
DISPLAY INVISIBLE (-5650 5675);
FORCEPROP 0 LAST CDS_SEC 1
J 0
(-5650 5675);
DISPLAY 1.021277 (-5650 5675);
DISPLAY INVISIBLE (-5650 5675);
FORCEPROP 1 LASTPIN (-5700 5600) $PN 1
J 0
(-5688 5612);
DISPLAY 0.489362 (-5688 5612);
PAINT MONO (-5688 5612);
FORCEPROP 1 LASTPIN (-5500 5600) $PN 2
J 0
(-5538 5612);
DISPLAY 0.489362 (-5538 5612);
PAINT MONO (-5538 5612);
FORCEPROP 1 LAST WATTAGE 1/16W
J 0
(-5500 5550);
DISPLAY 0.489362 (-5500 5550);
PAINT SKYBLUE (-5500 5550);
FORCEPROP 1 LAST TOLERANCE 5%
J 0
(-5475 5625);
DISPLAY 0.489362 (-5475 5625);
PAINT SKYBLUE (-5475 5625);
FORCEPROP 1 LAST PACK_TYPE 0402LF
J 0
(-5500 5525);
DISPLAY 0.489362 (-5500 5525);
PAINT SKYBLUE (-5500 5525);
FORCEPROP 1 LAST VALUE 0
J 2
(-5725 5625);
DISPLAY 0.489362 (-5725 5625);
PAINT SKYBLUE (-5725 5625);
FORCEPROP 1 LAST MATERIAL CHIP
J 0
(-5850 5525);
DISPLAY 0.489362 (-5850 5525);
PAINT SKYBLUE (-5850 5525);
FORCEPROP 2 LAST CDS_LIB pure_quanta
J 0
(-5600 5600);
DISPLAY INVISIBLE (-5600 5600);
FORCEPROP 1 LAST PATH I86
J 0
(-5650 5750);
DISPLAY 0.978723 (-5650 5750);
PAINT WHITE (-5650 5750);
DISPLAY INVISIBLE (-5650 5750);
FORCEPROP 1 LAST PART_NUMBER CS00002JB13
J 0
(-5850 5550);
DISPLAY 0.489362 (-5850 5550);
PAINT SKYBLUE (-5850 5550);
DISPLAY INVISIBLE (-5850 5550);
FORCEADD Q_RES..1
(-5600 5750);
FORCEPROP 1 LAST LOCATION R8304
J 0
(-5650 5800);
DISPLAY 0.489362 (-5650 5800);
PAINT SKYBLUE (-5650 5800);
FORCEPROP 0 LAST $SEC 1
J 0
(-5650 5825);
DISPLAY 0.680851 (-5650 5825);
PAINT MONO (-5650 5825);
DISPLAY INVISIBLE (-5650 5825);
FORCEPROP 0 LAST CDS_SEC 1
J 0
(-5650 5825);
DISPLAY 1.021277 (-5650 5825);
DISPLAY INVISIBLE (-5650 5825);
FORCEPROP 1 LASTPIN (-5700 5750) $PN 1
J 0
(-5688 5762);
DISPLAY 0.489362 (-5688 5762);
PAINT MONO (-5688 5762);
FORCEPROP 1 LASTPIN (-5500 5750) $PN 2
J 0
(-5538 5762);
DISPLAY 0.489362 (-5538 5762);
PAINT MONO (-5538 5762);
FORCEPROP 1 LAST MATERIAL CHIP
J 0
(-5850 5675);
DISPLAY 0.489362 (-5850 5675);
PAINT SKYBLUE (-5850 5675);
FORCEPROP 1 LAST PACK_TYPE 0402LF
J 0
(-5500 5675);
DISPLAY 0.489362 (-5500 5675);
PAINT SKYBLUE (-5500 5675);
FORCEPROP 1 LAST WATTAGE 1/16W
J 0
(-5500 5700);
DISPLAY 0.489362 (-5500 5700);
PAINT SKYBLUE (-5500 5700);
FORCEPROP 1 LAST VALUE 49.9
J 2
(-5725 5775);
DISPLAY 0.489362 (-5725 5775);
PAINT SKYBLUE (-5725 5775);
FORCEPROP 1 LAST TOLERANCE 1%
J 0
(-5475 5775);
DISPLAY 0.489362 (-5475 5775);
PAINT SKYBLUE (-5475 5775);
FORCEPROP 2 LAST CDS_LIB pure_quanta
J 0
(-5600 5750);
DISPLAY INVISIBLE (-5600 5750);
FORCEPROP 1 LAST PATH I87
J 0
(-5650 5900);
DISPLAY 0.978723 (-5650 5900);
PAINT WHITE (-5650 5900);
DISPLAY INVISIBLE (-5650 5900);
FORCEPROP 1 LAST PART_NUMBER CS04992FB07
J 0
(-5850 5700);
DISPLAY 0.489362 (-5850 5700);
PAINT SKYBLUE (-5850 5700);
DISPLAY INVISIBLE (-5850 5700);
FORCEADD Q_RES..1
(-5475 6350);
FORCEPROP 1 LAST LOCATION R8312
J 0
(-5525 6375);
DISPLAY 0.489362 (-5525 6375);
PAINT SKYBLUE (-5525 6375);
FORCEPROP 0 LAST $SEC 1
J 0
(-5350 6400);
DISPLAY 0.680851 (-5350 6400);
PAINT MONO (-5350 6400);
DISPLAY INVISIBLE (-5350 6400);
FORCEPROP 0 LAST CDS_SEC 1
J 0
(-5350 6400);
DISPLAY 1.021277 (-5350 6400);
DISPLAY INVISIBLE (-5350 6400);
FORCEPROP 1 LASTPIN (-5575 6350) $PN 1
J 0
(-5563 6362);
DISPLAY 0.489362 (-5563 6362);
PAINT MONO (-5563 6362);
FORCEPROP 1 LASTPIN (-5375 6350) $PN 2
J 0
(-5413 6362);
DISPLAY 0.489362 (-5413 6362);
PAINT MONO (-5413 6362);
FORCEPROP 1 LAST PACK_TYPE 0402LF
J 0
(-5375 6275);
DISPLAY 0.489362 (-5375 6275);
PAINT SKYBLUE (-5375 6275);
FORCEPROP 1 LAST TOLERANCE 5%
J 0
(-5350 6375);
DISPLAY 0.489362 (-5350 6375);
PAINT SKYBLUE (-5350 6375);
FORCEPROP 1 LAST VALUE 0
J 2
(-5600 6375);
DISPLAY 0.489362 (-5600 6375);
PAINT SKYBLUE (-5600 6375);
FORCEPROP 1 LAST WATTAGE 1/16W
J 0
(-5375 6300);
DISPLAY 0.489362 (-5375 6300);
PAINT SKYBLUE (-5375 6300);
FORCEPROP 1 LAST MATERIAL CHIP
J 0
(-5725 6275);
DISPLAY 0.489362 (-5725 6275);
PAINT SKYBLUE (-5725 6275);
FORCEPROP 2 LAST CDS_LIB pure_quanta
J 0
(-5475 6350);
DISPLAY INVISIBLE (-5475 6350);
FORCEPROP 1 LAST PATH I88
J 0
(-5525 6500);
DISPLAY 0.978723 (-5525 6500);
PAINT WHITE (-5525 6500);
DISPLAY INVISIBLE (-5525 6500);
FORCEPROP 1 LAST PART_NUMBER CS00002JB13
J 0
(-5725 6300);
DISPLAY 0.489362 (-5725 6300);
PAINT SKYBLUE (-5725 6300);
DISPLAY INVISIBLE (-5725 6300);
FORCEADD Q_RES..1
(-5475 6500);
FORCEPROP 1 LAST LOCATION R8311
J 0
(-5525 6550);
DISPLAY 0.489362 (-5525 6550);
PAINT SKYBLUE (-5525 6550);
FORCEPROP 0 LAST $SEC 1
J 0
(-5350 6550);
DISPLAY 0.680851 (-5350 6550);
PAINT MONO (-5350 6550);
DISPLAY INVISIBLE (-5350 6550);
FORCEPROP 0 LAST CDS_SEC 1
J 0
(-5350 6550);
DISPLAY 1.021277 (-5350 6550);
DISPLAY INVISIBLE (-5350 6550);
FORCEPROP 1 LASTPIN (-5575 6500) $PN 1
J 0
(-5563 6512);
DISPLAY 0.489362 (-5563 6512);
PAINT MONO (-5563 6512);
FORCEPROP 1 LASTPIN (-5375 6500) $PN 2
J 0
(-5413 6512);
DISPLAY 0.489362 (-5413 6512);
PAINT MONO (-5413 6512);
FORCEPROP 1 LAST MATERIAL CHIP
J 0
(-5725 6425);
DISPLAY 0.489362 (-5725 6425);
PAINT SKYBLUE (-5725 6425);
FORCEPROP 1 LAST PACK_TYPE 0402LF
J 0
(-5375 6425);
DISPLAY 0.489362 (-5375 6425);
PAINT SKYBLUE (-5375 6425);
FORCEPROP 1 LAST WATTAGE 1/16W
J 0
(-5375 6450);
DISPLAY 0.489362 (-5375 6450);
PAINT SKYBLUE (-5375 6450);
FORCEPROP 1 LAST TOLERANCE 5%
J 0
(-5350 6525);
DISPLAY 0.489362 (-5350 6525);
PAINT SKYBLUE (-5350 6525);
FORCEPROP 1 LAST VALUE 33
J 2
(-5600 6525);
DISPLAY 0.489362 (-5600 6525);
PAINT SKYBLUE (-5600 6525);
FORCEPROP 2 LAST CDS_LIB pure_quanta
J 0
(-5475 6500);
DISPLAY INVISIBLE (-5475 6500);
FORCEPROP 1 LAST PATH I89
J 0
(-5525 6650);
DISPLAY 0.978723 (-5525 6650);
PAINT WHITE (-5525 6650);
DISPLAY INVISIBLE (-5525 6650);
FORCEPROP 1 LAST PART_NUMBER CS03302JB10
J 0
(-5725 6450);
DISPLAY 0.489362 (-5725 6450);
PAINT SKYBLUE (-5725 6450);
DISPLAY INVISIBLE (-5725 6450);
FORCEADD OFFPAGE..4
R 2
(-8425 6050);
FORCEPROP 2 LAST $XR0 27 
J 0
(-8676 6050);
DISPLAY 0.638298 (-8676 6050);
PAINT MONO (-8676 6050);
FORCEPROP 2 LAST CDS_LIB standard
J 0
(-8425 6050);
DISPLAY INVISIBLE (-8425 6050);
FORCEPROP 1 LAST OFFPAGE TRUE
J 2
(-8750 5925);
DISPLAY 0.872340 (-8750 5925);
PAINT GREEN (-8750 5925);
DISPLAY INVISIBLE (-8750 5925);
FORCEPROP 1 LAST COMMENT_BODY TRUE
J 2
(-8400 5950);
DISPLAY 0.872340 (-8400 5950);
PAINT GREEN (-8400 5950);
DISPLAY INVISIBLE (-8400 5950);
FORCEPROP 2 LAST PATH I9
J 0
(-8625 6100);
DISPLAY 0.680851 (-8625 6100);
DISPLAY INVISIBLE (-8625 6100);
FORCEADD Q_CAP..2
(-4800 6225);
FORCEPROP 1 LAST LOCATION C468
J 1
(-4800 6275);
DISPLAY 0.489362 (-4800 6275);
PAINT SKYBLUE (-4800 6275);
FORCEPROP 0 LAST $SEC 1
J 0
(-4800 6325);
DISPLAY 0.680851 (-4800 6325);
PAINT MONO (-4800 6325);
DISPLAY INVISIBLE (-4800 6325);
FORCEPROP 0 LAST CDS_SEC 1
J 0
(-4800 6325);
DISPLAY 1.021277 (-4800 6325);
DISPLAY INVISIBLE (-4800 6325);
FORCEPROP 1 LASTPIN (-4900 6225) $PN 1
J 0
(-4910 6240);
DISPLAY 0.489362 (-4910 6240);
PAINT MONO (-4910 6240);
FORCEPROP 1 LASTPIN (-4700 6225) $PN 2
J 0
(-4715 6240);
DISPLAY 0.489362 (-4715 6240);
PAINT MONO (-4715 6240);
FORCEPROP 1 LAST VOLTAGE 50V
J 0
(-4650 6250);
DISPLAY 0.489362 (-4650 6250);
PAINT SKYBLUE (-4650 6250);
FORCEPROP 1 LAST PACK_TYPE 0402
J 0
(-4700 6200);
DISPLAY 0.489362 (-4700 6200);
PAINT SKYBLUE (-4700 6200);
FORCEPROP 1 LAST TOLERANCE 5%
J 0
(-4700 6175);
DISPLAY 0.489362 (-4700 6175);
PAINT SKYBLUE (-4700 6175);
FORCEPROP 1 LAST VALUE 1000PF
J 2
(-4975 6250);
DISPLAY 0.489362 (-4975 6250);
PAINT SKYBLUE (-4975 6250);
FORCEPROP 1 LAST MATERIAL X7R
J 0
(-5225 6175);
DISPLAY 0.489362 (-5225 6175);
PAINT SKYBLUE (-5225 6175);
FORCEPROP 2 LAST CDS_LIB pure_quanta
J 0
(-4800 6225);
DISPLAY INVISIBLE (-4800 6225);
FORCEPROP 1 LAST PATH I90
J 0
(-4800 6425);
DISPLAY 0.978723 (-4800 6425);
PAINT WHITE (-4800 6425);
DISPLAY INVISIBLE (-4800 6425);
FORCEPROP 1 LAST PART_NUMBER TMP_QCH21006JB10
J 0
(-5225 6200);
DISPLAY 0.489362 (-5225 6200);
PAINT SKYBLUE (-5225 6200);
DISPLAY INVISIBLE (-5225 6200);
FORCEADD UNIVERSAL_GND..1
(-4575 6150);
FORCEPROP 3 LASTPIN (-4575 6200) SIG_NAME GND\g
J 0
(-4565 6210);
DISPLAY 0.659574 (-4565 6210);
PAINT MONO (-4565 6210);
DISPLAY INVISIBLE (-4565 6210);
FORCEPROP 2 LAST CDS_LIB pure_quanta_power
J 0
(-4575 6150);
DISPLAY INVISIBLE (-4575 6150);
FORCEPROP 1 LAST HDL_POWER GND
J 1
(-4550 6075);
DISPLAY 0.872340 (-4550 6075);
PAINT GREEN (-4550 6075);
DISPLAY INVISIBLE (-4550 6075);
FORCEPROP 1 LAST PATH I91
J 0
(-4500 6150);
DISPLAY 0.872340 (-4500 6150);
PAINT AQUA (-4500 6150);
DISPLAY INVISIBLE (-4500 6150);
FORCEADD Q_CAP..2
(-4825 6775);
FORCEPROP 1 LAST LOCATION C467
J 1
(-4825 6850);
DISPLAY 0.489362 (-4825 6850);
PAINT SKYBLUE (-4825 6850);
FORCEPROP 0 LAST $SEC 1
J 0
(-4825 6875);
DISPLAY 0.680851 (-4825 6875);
PAINT MONO (-4825 6875);
DISPLAY INVISIBLE (-4825 6875);
FORCEPROP 0 LAST CDS_SEC 1
J 0
(-4825 6875);
DISPLAY 1.021277 (-4825 6875);
DISPLAY INVISIBLE (-4825 6875);
FORCEPROP 1 LASTPIN (-4925 6775) $PN 1
J 0
(-4935 6790);
DISPLAY 0.489362 (-4935 6790);
PAINT MONO (-4935 6790);
FORCEPROP 1 LASTPIN (-4725 6775) $PN 2
J 0
(-4740 6790);
DISPLAY 0.489362 (-4740 6790);
PAINT MONO (-4740 6790);
FORCEPROP 1 LAST VALUE 1000PF
J 2
(-4950 6825);
DISPLAY 0.489362 (-4950 6825);
PAINT SKYBLUE (-4950 6825);
FORCEPROP 1 LAST MATERIAL EMPTY
J 0
(-5100 6650);
DISPLAY 0.489362 (-5100 6650);
PAINT RED (-5100 6650);
FORCEPROP 1 LAST PACK_TYPE 0402
J 0
(-4700 6700);
DISPLAY 0.489362 (-4700 6700);
PAINT SKYBLUE (-4700 6700);
FORCEPROP 1 LAST VOLTAGE 50V
J 0
(-4725 6825);
DISPLAY 0.489362 (-4725 6825);
PAINT SKYBLUE (-4725 6825);
FORCEPROP 1 LAST TOLERANCE 5%
J 0
(-4700 6650);
DISPLAY 0.489362 (-4700 6650);
PAINT SKYBLUE (-4700 6650);
FORCEPROP 2 LAST CDS_LIB pure_quanta
J 0
(-4825 6775);
DISPLAY INVISIBLE (-4825 6775);
FORCEPROP 1 LAST PATH I92
J 0
(-4825 6975);
DISPLAY 0.978723 (-4825 6975);
PAINT WHITE (-4825 6975);
DISPLAY INVISIBLE (-4825 6975);
FORCEPROP 1 LAST PART_NUMBER TMP_QCH21006JB10
J 1
(-4975 6700);
DISPLAY 0.489362 (-4975 6700);
PAINT SKYBLUE (-4975 6700);
DISPLAY INVISIBLE (-4975 6700);
FORCEADD UNIVERSAL_GND..1
(-4575 6700);
FORCEPROP 3 LASTPIN (-4575 6750) SIG_NAME GND\g
J 0
(-4565 6760);
DISPLAY 0.659574 (-4565 6760);
PAINT MONO (-4565 6760);
DISPLAY INVISIBLE (-4565 6760);
FORCEPROP 2 LAST CDS_LIB pure_quanta_power
J 0
(-4575 6700);
DISPLAY INVISIBLE (-4575 6700);
FORCEPROP 1 LAST HDL_POWER GND
J 1
(-4550 6625);
DISPLAY 0.872340 (-4550 6625);
PAINT GREEN (-4550 6625);
DISPLAY INVISIBLE (-4550 6625);
FORCEPROP 1 LAST PATH I93
J 0
(-4500 6700);
DISPLAY 0.872340 (-4500 6700);
PAINT AQUA (-4500 6700);
DISPLAY INVISIBLE (-4500 6700);
FORCEADD UNIVERSAL_GND..1
(-2950 825);
FORCEPROP 3 LASTPIN (-2950 875) SIG_NAME GND\g
J 0
(-2940 885);
DISPLAY 0.659574 (-2940 885);
PAINT MONO (-2940 885);
DISPLAY INVISIBLE (-2940 885);
FORCEPROP 2 LAST CDS_LIB pure_quanta_power
J 0
(-2950 825);
DISPLAY INVISIBLE (-2950 825);
FORCEPROP 1 LAST HDL_POWER GND
J 1
(-2925 750);
DISPLAY 0.872340 (-2925 750);
PAINT GREEN (-2925 750);
DISPLAY INVISIBLE (-2925 750);
FORCEPROP 1 LAST PATH I94
J 0
(-2875 825);
DISPLAY 0.872340 (-2875 825);
PAINT AQUA (-2875 825);
DISPLAY INVISIBLE (-2875 825);
FORCEADD Q_CAP..1
(-2950 1100);
FORCEPROP 1 LAST LOCATION PC469
J 0
(-2900 1200);
DISPLAY 0.489362 (-2900 1200);
PAINT SKYBLUE (-2900 1200);
FORCEPROP 0 LAST $SEC 1
J 0
(-2900 1225);
DISPLAY 0.680851 (-2900 1225);
PAINT MONO (-2900 1225);
DISPLAY INVISIBLE (-2900 1225);
FORCEPROP 0 LAST CDS_SEC 1
J 0
(-2900 1225);
DISPLAY 1.021277 (-2900 1225);
DISPLAY INVISIBLE (-2900 1225);
FORCEPROP 1 LASTPIN (-2950 1200) $PN 1
J 0
(-2940 1180);
DISPLAY 0.489362 (-2940 1180);
PAINT MONO (-2940 1180);
FORCEPROP 1 LASTPIN (-2950 1000) $PN 2
J 0
(-2940 980);
DISPLAY 0.489362 (-2940 980);
PAINT MONO (-2940 980);
FORCEPROP 1 LAST MATERIAL X7R
J 0
(-2900 1000);
DISPLAY 0.489362 (-2900 1000);
PAINT SKYBLUE (-2900 1000);
FORCEPROP 1 LAST TOLERANCE 10%
J 0
(-2900 1050);
DISPLAY 0.489362 (-2900 1050);
PAINT SKYBLUE (-2900 1050);
FORCEPROP 1 LAST VALUE 470PF
J 0
(-2900 1150);
DISPLAY 0.489362 (-2900 1150);
PAINT SKYBLUE (-2900 1150);
FORCEPROP 1 LAST VOLTAGE 50V
J 0
(-2900 1100);
DISPLAY 0.489362 (-2900 1100);
PAINT SKYBLUE (-2900 1100);
FORCEPROP 1 LAST PACK_TYPE 0402
J 0
(-2900 900);
DISPLAY 0.489362 (-2900 900);
PAINT SKYBLUE (-2900 900);
FORCEPROP 2 LAST CDS_LIB pure_quanta
J 0
(-2950 1100);
DISPLAY INVISIBLE (-2950 1100);
FORCEPROP 1 LAST PATH I95
J 0
(-2900 1250);
DISPLAY 0.978723 (-2900 1250);
PAINT WHITE (-2900 1250);
DISPLAY INVISIBLE (-2900 1250);
FORCEPROP 1 LAST PART_NUMBER TMP_QCH14706KB18
J 0
(-2900 950);
DISPLAY 0.489362 (-2900 950);
PAINT SKYBLUE (-2900 950);
DISPLAY INVISIBLE (-2900 950);
FORCEADD OFFPAGE..4
(-2625 1300);
FORCEPROP 2 LAST $XR2 196 
J 0
(-2439 1336);
DISPLAY 0.638298 (-2439 1336);
PAINT MONO (-2439 1336);
FORCEPROP 2 LAST $XR1 195 
J 0
(-2439 1264);
DISPLAY 0.638298 (-2439 1264);
PAINT MONO (-2439 1264);
FORCEPROP 2 LAST $XR0 194 
J 0
(-2439 1300);
DISPLAY 0.638298 (-2439 1300);
PAINT MONO (-2439 1300);
FORCEPROP 2 LAST CDS_LIB standard
J 0
(-2625 1300);
DISPLAY INVISIBLE (-2625 1300);
FORCEPROP 1 LAST OFFPAGE TRUE
J 0
(-2300 1175);
DISPLAY 0.872340 (-2300 1175);
PAINT GREEN (-2300 1175);
DISPLAY INVISIBLE (-2300 1175);
FORCEPROP 1 LAST COMMENT_BODY TRUE
J 0
(-2650 1200);
DISPLAY 0.872340 (-2650 1200);
PAINT GREEN (-2650 1200);
DISPLAY INVISIBLE (-2650 1200);
FORCEPROP 2 LAST PATH I96
J 0
(-2425 1375);
DISPLAY 0.680851 (-2425 1375);
DISPLAY INVISIBLE (-2425 1375);
FORCEADD UNIVERSAL_GND..1
(-2325 1175);
FORCEPROP 3 LASTPIN (-2325 1225) SIG_NAME GND\g
J 0
(-2315 1235);
DISPLAY 0.659574 (-2315 1235);
PAINT MONO (-2315 1235);
DISPLAY INVISIBLE (-2315 1235);
FORCEPROP 2 LAST CDS_LIB pure_quanta_power
J 0
(-2325 1175);
DISPLAY INVISIBLE (-2325 1175);
FORCEPROP 1 LAST HDL_POWER GND
J 1
(-2300 1100);
DISPLAY 0.872340 (-2300 1100);
PAINT GREEN (-2300 1100);
DISPLAY INVISIBLE (-2300 1100);
FORCEPROP 1 LAST PATH I97
J 0
(-2250 1175);
DISPLAY 0.872340 (-2250 1175);
PAINT AQUA (-2250 1175);
DISPLAY INVISIBLE (-2250 1175);
FORCEADD Q_CAP..1
(-2325 1425);
FORCEPROP 1 LAST LOCATION PC472
J 0
(-2275 1525);
DISPLAY 0.489362 (-2275 1525);
PAINT SKYBLUE (-2275 1525);
FORCEPROP 0 LAST $SEC 1
J 0
(-2275 1550);
DISPLAY 0.680851 (-2275 1550);
PAINT MONO (-2275 1550);
DISPLAY INVISIBLE (-2275 1550);
FORCEPROP 0 LAST CDS_SEC 1
J 0
(-2275 1550);
DISPLAY 1.021277 (-2275 1550);
DISPLAY INVISIBLE (-2275 1550);
FORCEPROP 1 LASTPIN (-2325 1525) $PN 1
J 0
(-2315 1505);
DISPLAY 0.489362 (-2315 1505);
PAINT MONO (-2315 1505);
FORCEPROP 1 LASTPIN (-2325 1325) $PN 2
J 0
(-2315 1305);
DISPLAY 0.489362 (-2315 1305);
PAINT MONO (-2315 1305);
FORCEPROP 1 LAST TOLERANCE 10%
J 0
(-2275 1375);
DISPLAY 0.489362 (-2275 1375);
PAINT SKYBLUE (-2275 1375);
FORCEPROP 1 LAST VOLTAGE 50V
J 0
(-2275 1425);
DISPLAY 0.489362 (-2275 1425);
PAINT SKYBLUE (-2275 1425);
FORCEPROP 1 LAST PACK_TYPE 0402
J 0
(-2275 1225);
DISPLAY 0.489362 (-2275 1225);
PAINT SKYBLUE (-2275 1225);
FORCEPROP 1 LAST MATERIAL X7R
J 0
(-2275 1325);
DISPLAY 0.489362 (-2275 1325);
PAINT SKYBLUE (-2275 1325);
FORCEPROP 1 LAST VALUE 470PF
J 0
(-2275 1475);
DISPLAY 0.489362 (-2275 1475);
PAINT SKYBLUE (-2275 1475);
FORCEPROP 2 LAST CDS_LIB pure_quanta
J 0
(-2325 1425);
DISPLAY INVISIBLE (-2325 1425);
FORCEPROP 1 LAST PATH I98
J 0
(-2275 1575);
DISPLAY 0.978723 (-2275 1575);
PAINT WHITE (-2275 1575);
DISPLAY INVISIBLE (-2275 1575);
FORCEPROP 1 LAST PART_NUMBER TMP_QCH14706KB18
J 0
(-2275 1275);
DISPLAY 0.489362 (-2275 1275);
PAINT SKYBLUE (-2275 1275);
DISPLAY INVISIBLE (-2275 1275);
FORCEADD OFFPAGE..4
(-2375 2400);
FORCEPROP 2 LAST $XR0 198 
J 0
(-2189 2400);
DISPLAY 0.638298 (-2189 2400);
PAINT MONO (-2189 2400);
FORCEPROP 2 LAST CDS_LIB standard
J 0
(-2375 2400);
DISPLAY INVISIBLE (-2375 2400);
FORCEPROP 1 LAST OFFPAGE TRUE
J 0
(-2050 2275);
DISPLAY 0.872340 (-2050 2275);
PAINT GREEN (-2050 2275);
DISPLAY INVISIBLE (-2050 2275);
FORCEPROP 1 LAST COMMENT_BODY TRUE
J 0
(-2400 2300);
DISPLAY 0.872340 (-2400 2300);
PAINT GREEN (-2400 2300);
DISPLAY INVISIBLE (-2400 2300);
FORCEPROP 2 LAST PATH I99
J 0
(-2175 2450);
DISPLAY 0.680851 (-2175 2450);
DISPLAY INVISIBLE (-2175 2450);
FORCEADD DNS..1
(-7175 5400);
PAINT RED (-7175 5400);
FORCEPROP 2 LAST CDS_LIB mstr_misc
J 0
(-7175 5400);
DISPLAY INVISIBLE (-7175 5400);
FORCEPROP 1 LAST COMMENT_BODY TRUE
R 1
J 0
(-7100 5175);
DISPLAY 0.872340 (-7100 5175);
PAINT GREEN (-7100 5175);
DISPLAY INVISIBLE (-7100 5175);
FORCEADD DNS..1
(-7400 5400);
PAINT RED (-7400 5400);
FORCEPROP 2 LAST CDS_LIB mstr_misc
J 0
(-7400 5400);
DISPLAY INVISIBLE (-7400 5400);
FORCEPROP 1 LAST COMMENT_BODY TRUE
R 1
J 0
(-7325 5175);
DISPLAY 0.872340 (-7325 5175);
PAINT GREEN (-7325 5175);
DISPLAY INVISIBLE (-7325 5175);
FORCEADD DNS..1
(-7600 5375);
PAINT RED (-7600 5375);
FORCEPROP 2 LAST CDS_LIB mstr_misc
J 0
(-7600 5375);
DISPLAY INVISIBLE (-7600 5375);
FORCEPROP 1 LAST COMMENT_BODY TRUE
R 1
J 0
(-7525 5150);
DISPLAY 0.872340 (-7525 5150);
PAINT GREEN (-7525 5150);
DISPLAY INVISIBLE (-7525 5150);
FORCEADD DNS..1
(-6975 6350);
PAINT RED (-6975 6350);
FORCEPROP 2 LAST CDS_LIB mstr_misc
J 0
(-6975 6350);
DISPLAY INVISIBLE (-6975 6350);
FORCEPROP 1 LAST COMMENT_BODY TRUE
R 1
J 0
(-6900 6125);
DISPLAY 0.872340 (-6900 6125);
PAINT GREEN (-6900 6125);
DISPLAY INVISIBLE (-6900 6125);
FORCEADD DNS..1
(-7550 6350);
PAINT RED (-7550 6350);
FORCEPROP 2 LAST CDS_LIB mstr_misc
J 0
(-7550 6350);
DISPLAY INVISIBLE (-7550 6350);
FORCEPROP 1 LAST COMMENT_BODY TRUE
R 1
J 0
(-7475 6125);
DISPLAY 0.872340 (-7475 6125);
PAINT GREEN (-7475 6125);
DISPLAY INVISIBLE (-7475 6125);
FORCEADD DNS..1
(-7900 6350);
PAINT RED (-7900 6350);
FORCEPROP 2 LAST CDS_LIB mstr_misc
J 0
(-7900 6350);
DISPLAY INVISIBLE (-7900 6350);
FORCEPROP 1 LAST COMMENT_BODY TRUE
R 1
J 0
(-7825 6125);
DISPLAY 0.872340 (-7825 6125);
PAINT GREEN (-7825 6125);
DISPLAY INVISIBLE (-7825 6125);
FORCEADD DNS..1
(-7825 5400);
PAINT RED (-7825 5400);
FORCEPROP 2 LAST CDS_LIB mstr_misc
J 0
(-7825 5400);
DISPLAY INVISIBLE (-7825 5400);
FORCEPROP 1 LAST COMMENT_BODY TRUE
R 1
J 0
(-7750 5175);
DISPLAY 0.872340 (-7750 5175);
PAINT GREEN (-7750 5175);
DISPLAY INVISIBLE (-7750 5175);
FORCEADD DNS..1
(-7950 1550);
PAINT RED (-7950 1550);
FORCEPROP 2 LAST CDS_LIB mstr_misc
J 0
(-7950 1550);
DISPLAY INVISIBLE (-7950 1550);
FORCEPROP 1 LAST COMMENT_BODY TRUE
R 1
J 0
(-7875 1325);
DISPLAY 0.872340 (-7875 1325);
PAINT GREEN (-7875 1325);
DISPLAY INVISIBLE (-7875 1325);
FORCEADD DNS..1
(-4825 6750);
PAINT RED (-4825 6750);
FORCEPROP 2 LAST CDS_LIB mstr_misc
J 0
(-4825 6750);
DISPLAY INVISIBLE (-4825 6750);
FORCEPROP 1 LAST COMMENT_BODY TRUE
R 1
J 0
(-4750 6525);
DISPLAY 0.872340 (-4750 6525);
PAINT GREEN (-4750 6525);
DISPLAY INVISIBLE (-4750 6525);
FORCEADD DNS..1
(-5225 1625);
PAINT RED (-5225 1625);
FORCEPROP 2 LAST CDS_LIB mstr_misc
J 0
(-5225 1625);
DISPLAY INVISIBLE (-5225 1625);
FORCEPROP 1 LAST COMMENT_BODY TRUE
R 1
J 0
(-5150 1400);
DISPLAY 0.872340 (-5150 1400);
PAINT GREEN (-5150 1400);
DISPLAY INVISIBLE (-5150 1400);
FORCEADD DNS..1
(-5225 850);
PAINT RED (-5225 850);
FORCEPROP 2 LAST CDS_LIB mstr_misc
J 0
(-5225 850);
DISPLAY INVISIBLE (-5225 850);
FORCEPROP 1 LAST COMMENT_BODY TRUE
R 1
J 0
(-5150 625);
DISPLAY 0.872340 (-5150 625);
PAINT GREEN (-5150 625);
DISPLAY INVISIBLE (-5150 625);
FORCEADD QUANTA_TITLE_BLOCK_C..1
(400 350);
FORCEPROP 0 LAST CDS_CON_LAST_MODIFIED Thu Sep 14 16:12:17 2023
J 0
(-1485 365);
DISPLAY INVISIBLE (-1485 365);
FORCEPROP 1 LAST CUSTOM_TXT_CDS <CON_LAST_MODIFIED>
J 0
(-1485 365);
DISPLAY 0.978723 (-1485 365);
FORCEPROP 2 LAST CUSTOM_TXT_CDS <XR_PAGE_TITLE>
J 0
(-7490 5600);
DISPLAY 0.638298 (-7490 5600);
PAINT PINK (-7490 5600);
DISPLAY INVISIBLE (-7490 5600);
FORCEPROP 1 LAST CUSTOM_TXT_CDS <NAME_2>
J 0
(-2775 400);
FORCEPROP 1 LAST CUSTOM_TXT_CDS <NAME_1>
J 0
(-2775 525);
FORCEPROP 1 LAST CUSTOM_TXT_CDS <Q_NUMBER>
J 0
(-1003 453);
DISPLAY 1.212766 (-1003 453);
FORCEPROP 1 LAST CUSTOM_TXT_CDS <Q_PROJ>
J 0
(-1982 452);
DISPLAY 1.212766 (-1982 452);
FORCEPROP 1 LAST CUSTOM_TXT_CDS <Q_REV>
J 0
(216 453);
DISPLAY 1.212766 (216 453);
FORCEPROP 1 LAST CUSTOM_TXT_CDS <CON_PAGE_NUM> OF <CON_TOTAL_PAGES>
J 0
(-46 368);
DISPLAY 0.978723 (-46 368);
FORCEPROP 1 LAST Q_TITLE PVDDCR_CPU0_P0/PVDDCR_SOC_P0 VR CONTROLLER
J 0
(-8966 376);
DISPLAY 2.446809 (-8966 376);
PAINT GREEN (-8966 376);
FORCEPROP 2 LAST PAGE_BORDER TRUE
J 0
(-7490 5600);
DISPLAY 0.638298 (-7490 5600);
PAINT PINK (-7490 5600);
DISPLAY INVISIBLE (-7490 5600);
FORCEPROP 1 LAST CDS_LMAN_SYM_OUTLINE -9475,6775,100,-125
J 0
(400 350);
DISPLAY 0.468085 (400 350);
PAINT GREEN (400 350);
DISPLAY INVISIBLE (400 350);
FORCEPROP 2 LAST CDS_LIB pure_quanta
J 0
(400 350);
DISPLAY INVISIBLE (400 350);
FORCEPROP 2 LAST CDS_XR_PAGE_TITLE CR-193 : @T6G_MB_LIB.T6G(SCH_1):PAGE193
J 0
(-7490 5600);
DISPLAY 0.638298 (-7490 5600);
PAINT PINK (-7490 5600);
DISPLAY INVISIBLE (-7490 5600);
FORCEPROP 1 LAST Q_DEPT BU9
J 1
(-3363 399);
DISPLAY 1.957447 (-3363 399);
PAINT GREEN (-3363 399);
DISPLAY INVISIBLE (-3363 399);
FORCEPROP 1 LAST COMMENT_BODY TRUE
J 0
(412 337);
DISPLAY 0.978723 (412 337);
PAINT GREEN (412 337);
DISPLAY INVISIBLE (412 337);
FORCEADD DNS..1
(-7250 6350);
PAINT RED (-7250 6350);
FORCEPROP 2 LAST CDS_LIB mstr_misc
J 0
(-7250 6350);
DISPLAY INVISIBLE (-7250 6350);
FORCEPROP 1 LAST COMMENT_BODY TRUE
R 1
J 0
(-7175 6125);
DISPLAY 0.872340 (-7175 6125);
PAINT GREEN (-7175 6125);
DISPLAY INVISIBLE (-7175 6125);
WIRE 16 -1 (-2775 5950)(-2775 5875);
WIRE 16 -1 (-2775 6425)(-2775 6325);
WIRE 16 -1 (-2500 5875)(-2500 5950);
WIRE 16 -1 (-2475 6325)(-2475 6425);
WIRE 16 -1 (-6850 1525)(-7000 1525);
WIRE 16 -1 (-6550 6625)(-6700 6625);
WIRE 16 -1 (-5225 4675)(-5225 4625);
WIRE 16 -1 (-5950 4725)(-5425 4725);
WIRE 16 -1 (-6525 925)(-6525 850);
WIRE 16 -1 (-6050 925)(-6050 850);
WIRE 16 -1 (-8100 5325)(-8100 5225);
WIRE 16 -1 (-6625 2825)(-6625 2775);
WIRE 16 -1 (-6625 3625)(-6625 3650);
WIRE 16 -1 (-6625 3925)(-6625 3875);
WIRE 16 -1 (-5250 750)(-5250 700);
WIRE 16 -1 (-4875 775)(-4875 700);
WIRE 16 -1 (-7850 5225)(-7850 5325);
WIRE 16 -1 (-5150 2125)(-4900 2125);
WIRE 16 -1 (-7625 5325)(-7625 5225);
WIRE 16 -1 (-7400 5325)(-7400 5225);
WIRE 16 -1 (-7175 5325)(-7175 5225);
WIRE 16 -1 (-6625 4750)(-6625 4800);
WIRE 16 -1 (-2950 1000)(-2950 875);
WIRE 16 -1 (-2325 1225)(-2325 1325);
WIRE 16 -1 (-4600 4200)(-5325 4200);
WIRE 16 -1 (-5325 4225)(-5325 4200);
WIRE 16 -1 (-5325 4200)(-6625 4200);
WIRE 16 -1 (-6625 4125)(-6625 4200);
WIRE 16 -1 (-7325 4200)(-6625 4200);
FORCEPROP 2 LAST SIG_NAME VSENSE_VSS_SENSE_A_P0
J 2
(-6835 4210);
DISPLAY 0.489362 (-6835 4210);
WIRE 16 -1 (-8375 5750)(-7850 5750);
WIRE 16 -1 (-7625 5750)(-7850 5750);
WIRE 16 -1 (-7850 5750)(-7850 5525);
WIRE 16 -1 (-7550 5750)(-7625 5750);
WIRE 16 -1 (-7625 5525)(-7625 5750);
WIRE 16 -1 (-5700 5750)(-7550 5750);
FORCEPROP 2 LAST SIG_NAME SVID_PVDDCR_CPU0_P0_SVTO
J 0
(-6585 5760);
DISPLAY 0.489362 (-6585 5760);
WIRE 16 -1 (-7550 6275)(-7550 5750);
WIRE 16 -1 (-8375 5900)(-7400 5900);
WIRE 16 -1 (-7250 5900)(-7400 5900);
WIRE 16 -1 (-7400 5525)(-7400 5900);
WIRE 16 -1 (-7250 5900)(-5700 5900);
FORCEPROP 2 LAST SIG_NAME SVID_PVDDCR_CPU0_P0_SVD_R
J 0
(-6735 5910);
DISPLAY 0.489362 (-6735 5910);
WIRE 16 -1 (-7250 6275)(-7250 5900);
WIRE 16 -1 (-6975 6050)(-5725 6050);
FORCEPROP 2 LAST SIG_NAME SVID_PVDDCR_CPU0_P0_SVC_R
J 0
(-6710 6060);
DISPLAY 0.489362 (-6710 6060);
WIRE 16 -1 (-6975 6275)(-6975 6050);
WIRE 16 -1 (-6975 6050)(-7175 6050);
WIRE 16 -1 (-7175 5525)(-7175 6050);
WIRE 16 -1 (-7175 6050)(-8375 6050);
WIRE 17 273 (-7575 3600)(-6725 3600);
WIRE 17 273 (-7575 3600)(-7575 2790);
WIRE 17 273 (-6725 3600)(-6725 2790);
WIRE 17 273 (-7575 2790)(-6725 2790);
WIRE 16 -1 (-5625 3350)(-6625 3350);
WIRE 16 -1 (-6625 3425)(-6625 3350);
WIRE 16 -1 (-7325 3350)(-6625 3350);
FORCEPROP 2 LAST SIG_NAME VSENSE_PVDDCR_SOC_P0_DP
J 2
(-6785 3360);
DISPLAY 0.489362 (-6785 3360);
WIRE 16 -1 (-5250 3100)(-4600 3100);
WIRE 16 -1 (-5250 3125)(-5250 3100);
WIRE 16 -1 (-5250 3100)(-6625 3100);
WIRE 16 -1 (-6625 3025)(-6625 3100);
WIRE 16 -1 (-7325 3100)(-6625 3100);
FORCEPROP 2 LAST SIG_NAME VSENSE_VSS_SENSE_A_P0
J 2
(-6835 3110);
DISPLAY 0.489362 (-6835 3110);
WIRE 16 -1 (-5450 2500)(-4750 2500);
FORCEPROP 2 LAST SIG_NAME PVDDCR_CPU0_P0_OCP_N_R
J 0
(-5260 2510);
DISPLAY 0.489362 (-5260 2510);
FORCEPROP 2 LASTPROP $XRERR UNIQUE?
J 0
(-5500 2510);
DISPLAY 0.638298 (-5500 2510);
PAINT MONO (-5500 2510);
DISPLAY INVISIBLE (-5500 2510);
WIRE 16 -1 (-4600 2500)(-4750 2500);
WIRE 16 -1 (-4750 2375)(-4750 2500);
WIRE 16 -1 (-4900 2375)(-4750 2375);
WIRE 17 273 (-7575 4675)(-6725 4675);
WIRE 17 273 (-7575 4675)(-7575 3865);
WIRE 17 273 (-6725 4675)(-6725 3865);
WIRE 17 273 (-7575 3865)(-6725 3865);
WIRE 16 -1 (-3250 3300)(-2600 3300);
FORCEPROP 2 LAST SIG_NAME NC_PVDDCR_CPU0_P0_IMON8
J 2
(-2635 3310);
DISPLAY 0.489362 (-2635 3310);
FORCEPROP 2 LASTPROP $XRERR UNIQUE?
J 0
(-2875 3310);
DISPLAY 0.638298 (-2875 3310);
PAINT MONO (-2875 3310);
DISPLAY INVISIBLE (-2875 3310);
WIRE 17 273 (-1250 5600)(350 5600);
WIRE 17 273 (-1250 5600)(-1250 4400);
WIRE 17 273 (350 5600)(350 4400);
WIRE 17 273 (-1250 4400)(350 4400);
WIRE 17 273 (-1250 6975)(350 6975);
WIRE 17 273 (-1250 6975)(-1250 5675);
WIRE 17 273 (350 6975)(350 5675);
WIRE 17 273 (-1250 5675)(350 5675);
WIRE 16 -1 (-3250 5400)(-2425 5400);
FORCEPROP 2 LAST SIG_NAME PVDDCR_CPU0_P0_IMON1
J 2
(-2635 5410);
DISPLAY 0.489362 (-2635 5410);
WIRE 16 -1 (-3250 6500)(-3025 6500);
WIRE 16 -1 (-3025 6500)(-3025 6675);
WIRE 16 -1 (-3025 6675)(-2775 6675);
WIRE 16 -1 (-2775 6675)(-2475 6675);
FORCEPROP 2 LAST SIG_NAME PVDDCR_CPU0_P0_VCC
J 2
(-2535 6700);
DISPLAY 0.489362 (-2535 6700);
FORCEPROP 2 LASTPROP $XRERR UNIQUE?
J 0
(-2775 6700);
DISPLAY 0.638298 (-2775 6700);
PAINT MONO (-2775 6700);
DISPLAY INVISIBLE (-2775 6700);
WIRE 16 -1 (-2775 6675)(-2775 6625);
WIRE 16 -1 (-2150 6675)(-2475 6675);
WIRE 16 -1 (-2475 6625)(-2475 6675);
WIRE 16 -1 (-4600 5600)(-5500 5600);
FORCEPROP 2 LAST SIG_NAME SVID_PVDDCR_CPU0_P0_SVTI_R
J 0
(-5285 5610);
DISPLAY 0.489362 (-5285 5610);
FORCEPROP 2 LASTPROP $XRERR UNIQUE?
J 0
(-5525 5610);
DISPLAY 0.638298 (-5525 5610);
PAINT MONO (-5525 5610);
DISPLAY INVISIBLE (-5525 5610);
WIRE 16 -1 (-5400 5350)(-4600 5350);
FORCEPROP 2 LAST SIG_NAME PVDDCR_CPU0_P0_PMSCL_R
J 2
(-4685 5360);
DISPLAY 0.489362 (-4685 5360);
FORCEPROP 2 LASTPROP $XRERR UNIQUE?
J 0
(-4925 5360);
DISPLAY 0.638298 (-4925 5360);
PAINT MONO (-4925 5360);
DISPLAY INVISIBLE (-4925 5360);
WIRE 16 -1 (-5525 6050)(-4600 6050);
FORCEPROP 2 LAST SIG_NAME SVID_PVDDCR_CPU0_P0_SVC_R1
J 0
(-5360 6060);
DISPLAY 0.553191 (-5360 6060);
FORCEPROP 2 LASTPROP $XRERR UNIQUE?
J 0
(-5600 6060);
DISPLAY 0.638298 (-5600 6060);
PAINT MONO (-5600 6060);
DISPLAY INVISIBLE (-5600 6060);
WIRE 16 -1 (-3250 3900)(-2425 3900);
FORCEPROP 2 LAST SIG_NAME PVDDCR_CPU0_P0_IMON6
J 2
(-2635 3910);
DISPLAY 0.489362 (-2635 3910);
WIRE 16 -1 (-4600 5750)(-5500 5750);
FORCEPROP 2 LAST SIG_NAME SVID_PVDDCR_CPU0_P0_SVTO_R
J 0
(-5285 5760);
DISPLAY 0.489362 (-5285 5760);
FORCEPROP 2 LASTPROP $XRERR UNIQUE?
J 0
(-5525 5760);
DISPLAY 0.638298 (-5525 5760);
PAINT MONO (-5525 5760);
DISPLAY INVISIBLE (-5525 5760);
WIRE 16 -1 (-5450 2650)(-5350 2650);
WIRE 16 -1 (-4600 2650)(-5350 2650);
FORCEPROP 2 LAST SIG_NAME PVDDCR_CPU0_P0_RESET_N_R
J 0
(-5285 2660);
DISPLAY 0.489362 (-5285 2660);
FORCEPROP 2 LASTPROP $XRERR UNIQUE?
J 0
(-5525 2660);
DISPLAY 0.638298 (-5525 2660);
PAINT MONO (-5525 2660);
DISPLAY INVISIBLE (-5525 2660);
WIRE 16 -1 (-5350 2800)(-5350 2650);
WIRE 16 -1 (-5600 2800)(-5350 2800);
WIRE 16 -1 (-3250 3600)(-2600 3600);
FORCEPROP 2 LAST SIG_NAME NC_PVDDCR_CPU0_P0_IMON7
J 2
(-2635 3610);
DISPLAY 0.489362 (-2635 3610);
FORCEPROP 2 LASTPROP $XRERR UNIQUE?
J 0
(-2875 3610);
DISPLAY 0.638298 (-2875 3610);
PAINT MONO (-2875 3610);
DISPLAY INVISIBLE (-2875 3610);
WIRE 16 -1 (-4600 1250)(-4900 1250);
WIRE 16 -1 (-4900 1250)(-4900 1400);
WIRE 16 -1 (-5625 1400)(-4900 1400);
FORCEPROP 2 LAST SIG_NAME PWRGD_PVDDCR_SOC_P0_R
J 2
(-5060 1410);
DISPLAY 0.489362 (-5060 1410);
FORCEPROP 2 LASTPROP $XRERR UNIQUE?
J 0
(-5300 1410);
DISPLAY 0.638298 (-5300 1410);
PAINT MONO (-5300 1410);
DISPLAY INVISIBLE (-5300 1410);
WIRE 16 -1 (-5625 1650)(-5625 1400);
WIRE 16 -1 (-5625 1400)(-5800 1400);
WIRE 16 -1 (-5625 1650)(-5325 1650);
WIRE 16 -1 (-5800 1650)(-5625 1650);
WIRE 16 -1 (-5500 5900)(-4600 5900);
FORCEPROP 2 LAST SIG_NAME SVID_PVDDCR_CPU0_P0_SVD_R1
J 0
(-5360 5910);
DISPLAY 0.553191 (-5360 5910);
FORCEPROP 2 LASTPROP $XRERR UNIQUE?
J 0
(-5600 5910);
DISPLAY 0.638298 (-5600 5910);
PAINT MONO (-5600 5910);
DISPLAY INVISIBLE (-5600 5910);
WIRE 16 -1 (-5400 5050)(-4600 5050);
FORCEPROP 2 LAST SIG_NAME PVDDCR_CPU0_P0_PMALERT_R
J 2
(-4685 5060);
DISPLAY 0.489362 (-4685 5060);
FORCEPROP 2 LASTPROP $XRERR UNIQUE?
J 0
(-4925 5060);
DISPLAY 0.638298 (-4925 5060);
PAINT MONO (-4925 5060);
DISPLAY INVISIBLE (-4925 5060);
WIRE 16 -1 (-5375 6350)(-5200 6350);
WIRE 16 -1 (-5200 6350)(-4600 6350);
FORCEPROP 2 LAST SIG_NAME PVDDCR_CPU0_P0_EN_R
J 2
(-4710 6360);
DISPLAY 0.489362 (-4710 6360);
FORCEPROP 2 LASTPROP $XRERR UNIQUE?
J 0
(-4950 6360);
DISPLAY 0.638298 (-4950 6360);
PAINT MONO (-4950 6360);
DISPLAY INVISIBLE (-4950 6360);
WIRE 16 -1 (-5200 6225)(-5200 6350);
WIRE 16 -1 (-4900 6225)(-5200 6225);
WIRE 16 -1 (-5400 5200)(-4600 5200);
FORCEPROP 2 LAST SIG_NAME PVDDCR_CPU0_P0_PMSDA_R
J 2
(-4685 5210);
DISPLAY 0.489362 (-4685 5210);
FORCEPROP 2 LASTPROP $XRERR UNIQUE?
J 0
(-4925 5210);
DISPLAY 0.638298 (-4925 5210);
PAINT MONO (-4925 5210);
DISPLAY INVISIBLE (-4925 5210);
WIRE 16 -1 (-3250 3400)(-2425 3400);
FORCEPROP 2 LAST SIG_NAME NC_PVDDCR_CPU0_P0_PWM8
J 2
(-2660 3410);
DISPLAY 0.489362 (-2660 3410);
FORCEPROP 2 LASTPROP $XRERR UNIQUE?
J 0
(-2395 3400);
DISPLAY 0.638298 (-2395 3400);
PAINT MONO (-2395 3400);
DISPLAY INVISIBLE (-2395 3400);
WIRE 16 -1 (-3250 3700)(-2425 3700);
FORCEPROP 2 LAST SIG_NAME NC_PVDDCR_CPU0_P0_PWM7
J 2
(-2660 3710);
DISPLAY 0.489362 (-2660 3710);
FORCEPROP 2 LASTPROP $XRERR UNIQUE?
J 0
(-2395 3700);
DISPLAY 0.638298 (-2395 3700);
PAINT MONO (-2395 3700);
DISPLAY INVISIBLE (-2395 3700);
WIRE 16 -1 (-5325 4425)(-5325 4450);
WIRE 16 -1 (-4600 4450)(-5325 4450);
FORCEPROP 2 LAST SIG_NAME VSENSE_PVDDCR_CPU0_P0_VSEN0
J 2
(-4710 4460);
DISPLAY 0.489362 (-4710 4460);
FORCEPROP 2 LASTPROP $XRERR UNIQUE?
J 0
(-4950 4460);
DISPLAY 0.638298 (-4950 4460);
PAINT MONO (-4950 4460);
DISPLAY INVISIBLE (-4950 4460);
WIRE 16 -1 (-5500 4450)(-5325 4450);
WIRE 16 -1 (-3250 2500)(-2425 2500);
FORCEPROP 2 LAST SIG_NAME PVDDCR_SOC_P0_PWM2
J 2
(-2650 2510);
DISPLAY 0.489362 (-2650 2510);
WIRE 16 -1 (-5200 6500)(-4600 6500);
FORCEPROP 2 LAST SIG_NAME PWRGD_PVDDCR_CPU0_P0_R
J 2
(-4685 6510);
DISPLAY 0.489362 (-4685 6510);
FORCEPROP 2 LASTPROP $XRERR UNIQUE?
J 0
(-4925 6510);
DISPLAY 0.638298 (-4925 6510);
PAINT MONO (-4925 6510);
DISPLAY INVISIBLE (-4925 6510);
WIRE 16 -1 (-5200 6775)(-5200 6500);
WIRE 16 -1 (-5200 6500)(-5375 6500);
WIRE 16 -1 (-5200 6775)(-4925 6775);
WIRE 16 -1 (-5600 6775)(-5200 6775);
WIRE 16 -1 (-3250 4000)(-2425 4000);
FORCEPROP 2 LAST SIG_NAME PVDDCR_CPU0_P0_PWM6
J 2
(-2660 4010);
DISPLAY 0.489362 (-2660 4010);
WIRE 16 -1 (-2500 6200)(-2100 6200);
FORCEPROP 2 LAST SIG_NAME PVDDCR_CPU0_P0_VCCS
J 2
(-2485 6210);
DISPLAY 0.489362 (-2485 6210);
WIRE 16 -1 (-2500 6150)(-2500 6200);
WIRE 16 -1 (-2500 6200)(-2775 6200);
WIRE 16 -1 (-2775 6200)(-2775 6150);
WIRE 16 -1 (-2775 6200)(-3250 6200);
WIRE 16 -1 (-5225 1150)(-4600 1150);
FORCEPROP 2 LAST SIG_NAME PVDDCR_CPU0_P0_VMON
J 2
(-4735 1160);
DISPLAY 0.489362 (-4735 1160);
FORCEPROP 2 LASTPROP $XRERR UNIQUE?
J 0
(-4975 1160);
DISPLAY 0.638298 (-4975 1160);
PAINT MONO (-4975 1160);
DISPLAY INVISIBLE (-4975 1160);
WIRE 16 -1 (-5225 1225)(-5225 1150);
WIRE 16 -1 (-5225 1225)(-6050 1225);
WIRE 16 -1 (-6050 1125)(-6050 1225);
WIRE 16 -1 (-6050 1225)(-6525 1225);
WIRE 16 -1 (-6525 1125)(-6525 1225);
WIRE 16 -1 (-6725 1225)(-6525 1225);
WIRE 16 -1 (-4875 975)(-4875 1050);
WIRE 16 -1 (-4600 1050)(-4875 1050);
FORCEPROP 2 LAST SIG_NAME PVDDCR_CPU0_P0_VINSEN
J 2
(-4710 1060);
DISPLAY 0.489362 (-4710 1060);
FORCEPROP 2 LASTPROP $XRERR UNIQUE?
J 0
(-4950 1060);
DISPLAY 0.638298 (-4950 1060);
PAINT MONO (-4950 1060);
DISPLAY INVISIBLE (-4950 1060);
WIRE 16 -1 (-5250 1050)(-4875 1050);
WIRE 16 -1 (-5450 1050)(-5250 1050);
WIRE 16 -1 (-5250 950)(-5250 1050);
WIRE 16 -1 (-2675 1300)(-2950 1300);
FORCEPROP 2 LAST SIG_NAME PVDDCR_CPU0_P0_TEMP0
J 2
(-2660 1310);
DISPLAY 0.489362 (-2660 1310);
WIRE 16 -1 (-2950 1200)(-2950 1300);
WIRE 16 -1 (-2950 1300)(-3250 1300);
WIRE 16 -1 (-5100 2375)(-5650 2375);
WIRE 16 -1 (-5650 2375)(-5650 2250);
WIRE 16 -1 (-4600 2250)(-5650 2250);
WIRE 16 -1 (-5650 2125)(-5650 2250);
WIRE 16 -1 (-5350 2125)(-5650 2125);
WIRE 16 -1 (-5650 2125)(-5850 2125);
WIRE 16 -1 (-5850 2125)(-5850 2150);
WIRE 16 -1 (-5250 3325)(-5250 3350);
WIRE 16 -1 (-5250 3350)(-4600 3350);
FORCEPROP 2 LAST SIG_NAME VSENSE_PVDDCR_SOC_P0_VSEN1
J 2
(-4710 3360);
DISPLAY 0.489362 (-4710 3360);
FORCEPROP 2 LASTPROP $XRERR UNIQUE?
J 0
(-4950 3360);
DISPLAY 0.638298 (-4950 3360);
PAINT MONO (-4950 3360);
DISPLAY INVISIBLE (-4950 3360);
WIRE 16 -1 (-5425 3350)(-5250 3350);
WIRE 16 -1 (-3250 2400)(-2425 2400);
FORCEPROP 2 LAST SIG_NAME PVDDCR_SOC_P0_IMON2
J 2
(-2650 2410);
DISPLAY 0.489362 (-2650 2410);
WIRE 16 -1 (-3250 5500)(-2425 5500);
FORCEPROP 2 LAST SIG_NAME PVDDCR_CPU0_P0_PWM1
J 2
(-2660 5510);
DISPLAY 0.489362 (-2660 5510);
WIRE 16 -1 (-3250 3100)(-2425 3100);
FORCEPROP 2 LAST SIG_NAME NC_PVDDCR_CPU0_P0_PWM9
J 2
(-2635 3110);
DISPLAY 0.489362 (-2635 3110);
FORCEPROP 2 LASTPROP $XRERR UNIQUE?
J 0
(-2395 3100);
DISPLAY 0.638298 (-2395 3100);
PAINT MONO (-2395 3100);
DISPLAY INVISIBLE (-2395 3100);
WIRE 16 -1 (-3250 3000)(-2600 3000);
FORCEPROP 2 LAST SIG_NAME NC_PVDDCR_CPU0_P0_IMON9
J 2
(-2635 3010);
DISPLAY 0.489362 (-2635 3010);
FORCEPROP 2 LASTPROP $XRERR UNIQUE?
J 0
(-2875 3010);
DISPLAY 0.638298 (-2875 3010);
PAINT MONO (-2875 3010);
DISPLAY INVISIBLE (-2875 3010);
WIRE 16 -1 (-3250 2800)(-2425 2800);
FORCEPROP 2 LAST SIG_NAME PVDDCR_SOC_P0_PWM3
J 2
(-2650 2810);
DISPLAY 0.489362 (-2650 2810);
WIRE 16 -1 (-3250 2700)(-2425 2700);
FORCEPROP 2 LAST SIG_NAME PVDDCR_SOC_P0_IMON3
J 2
(-2650 2710);
DISPLAY 0.489362 (-2650 2710);
WIRE 16 -1 (-4675 950)(-4600 950);
WIRE 16 -1 (-4675 900)(-4675 950);
WIRE 16 -1 (-5400 1750)(-4600 1750);
FORCEPROP 2 LAST SIG_NAME PVDDCR_SOC_P0_EN//ADDR_CFG
J 2
(-4710 1760);
DISPLAY 0.489362 (-4710 1760);
FORCEPROP 2 LASTPROP $XRERR UNIQUE?
J 0
(-4950 1760);
DISPLAY 0.638298 (-4950 1760);
PAINT MONO (-4950 1760);
DISPLAY INVISIBLE (-4950 1760);
WIRE 16 -1 (-5400 1900)(-5400 1750);
WIRE 16 -1 (-6675 1900)(-5400 1900);
WIRE 16 -1 (-6675 1900)(-6675 1875);
WIRE 16 -1 (-6675 1950)(-6675 1900);
WIRE 16 -1 (-2325 1600)(-2100 1600);
WIRE 16 -1 (-2325 1525)(-2325 1600);
WIRE 16 -1 (-2325 1600)(-3250 1600);
FORCEPROP 2 LAST SIG_NAME PVDDCR_SOC_P0_TEMP1
J 2
(-2610 1610);
DISPLAY 0.489362 (-2610 1610);
WIRE 16 -1 (-3250 2200)(-2425 2200);
FORCEPROP 2 LAST SIG_NAME PVDDCR_SOC_P0_PWM1
J 2
(-2650 2210);
DISPLAY 0.489362 (-2650 2210);
WIRE 16 -1 (-3250 2100)(-2425 2100);
FORCEPROP 2 LAST SIG_NAME PVDDCR_SOC_P0_IMON1
J 2
(-2650 2110);
DISPLAY 0.489362 (-2650 2110);
WIRE 16 -1 (-3250 4300)(-2425 4300);
FORCEPROP 2 LAST SIG_NAME PVDDCR_CPU0_P0_PWM5
J 2
(-2660 4310);
DISPLAY 0.489362 (-2660 4310);
WIRE 16 -1 (-3250 4200)(-2425 4200);
FORCEPROP 2 LAST SIG_NAME PVDDCR_CPU0_P0_IMON5
J 2
(-2635 4210);
DISPLAY 0.489362 (-2635 4210);
WIRE 16 -1 (-3250 4600)(-2425 4600);
FORCEPROP 2 LAST SIG_NAME PVDDCR_CPU0_P0_PWM4
J 2
(-2660 4610);
DISPLAY 0.489362 (-2660 4610);
WIRE 16 -1 (-3250 4500)(-2425 4500);
FORCEPROP 2 LAST SIG_NAME PVDDCR_CPU0_P0_IMON4
J 2
(-2635 4510);
DISPLAY 0.489362 (-2635 4510);
WIRE 16 -1 (-3250 4900)(-2425 4900);
FORCEPROP 2 LAST SIG_NAME PVDDCR_CPU0_P0_PWM3
J 2
(-2660 4910);
DISPLAY 0.489362 (-2660 4910);
WIRE 16 -1 (-3250 4800)(-2425 4800);
FORCEPROP 2 LAST SIG_NAME PVDDCR_CPU0_P0_IMON3
J 2
(-2635 4810);
DISPLAY 0.489362 (-2635 4810);
WIRE 16 -1 (-3250 5200)(-2425 5200);
FORCEPROP 2 LAST SIG_NAME PVDDCR_CPU0_P0_PWM2
J 2
(-2660 5210);
DISPLAY 0.489362 (-2660 5210);
WIRE 16 -1 (-3250 5100)(-2425 5100);
FORCEPROP 2 LAST SIG_NAME PVDDCR_CPU0_P0_IMON2
J 2
(-2635 5110);
DISPLAY 0.489362 (-2635 5110);
WIRE 16 -1 (-7900 6275)(-7900 5600);
WIRE 16 -1 (-5700 5600)(-7900 5600);
FORCEPROP 2 LAST SIG_NAME SVID_PVDDCR_CPU0_P0_SVTI
J 0
(-6585 5625);
DISPLAY 0.489362 (-6585 5625);
FORCEPROP 2 LASTPROP $XRERR UNIQUE?
J 0
(-6825 5625);
DISPLAY 0.638298 (-6825 5625);
PAINT MONO (-6825 5625);
DISPLAY INVISIBLE (-6825 5625);
WIRE 16 -1 (-8100 5600)(-7900 5600);
WIRE 16 -1 (-8100 5600)(-8100 5525);
WIRE 16 -1 (-4575 6750)(-4575 6775);
WIRE 16 -1 (-4575 6775)(-4725 6775);
WIRE 16 -1 (-4575 6200)(-4575 6225);
WIRE 16 -1 (-4575 6225)(-4700 6225);
WIRE 16 -1 (-6100 6775)(-5800 6775);
WIRE 16 -1 (-6100 6850)(-6100 6775);
WIRE 16 -1 (-4900 1575)(-4900 1650);
WIRE 16 -1 (-4900 1650)(-5125 1650);
WIRE 16 -1 (-6150 2800)(-5800 2800);
WIRE 16 -1 (-6150 2875)(-6150 2800);
WIRE 16 -1 (-6675 2550)(-6675 2575);
WIRE 16 -1 (-6675 2575)(-7350 2575);
WIRE 16 -1 (-7350 2525)(-7350 2575);
WIRE 16 -1 (-7350 2575)(-7350 2600);
WIRE 16 -1 (-6175 1650)(-6000 1650);
WIRE 16 -1 (-6175 1750)(-6175 1650);
WIRE 16 -1 (-7350 1650)(-6675 1650);
WIRE 16 -1 (-7350 1650)(-7350 1725);
WIRE 16 -1 (-6675 1675)(-6675 1650);
WIRE 16 -1 (-6675 1625)(-6675 1650);
WIRE 16 -1 (-5750 1075)(-5750 1050);
WIRE 16 -1 (-5750 1050)(-5650 1050);
WIRE 16 -1 (-7125 1300)(-7125 1225);
WIRE 16 -1 (-7125 1225)(-6925 1225);
WIRE 16 -1 (-1625 6725)(-1625 6675);
WIRE 16 -1 (-1625 6675)(-1950 6675);
WIRE 16 -1 (-7950 1475)(-7950 1450);
WIRE 16 -1 (-7950 1450)(-7675 1450);
FORCEPROP 0 LAST VOLTAGE 0
J 0
(-7912 1450);
DISPLAY INVISIBLE (-7912 1450);
WIRE 16 -1 (-7675 1500)(-7675 1450);
WIRE 16 -1 (-7675 1450)(-7675 1400);
WIRE 16 -1 (-2150 3200)(-2150 3300);
WIRE 16 -1 (-2150 3300)(-2400 3300);
WIRE 16 -1 (-7900 6475)(-7900 6575);
WIRE 16 -1 (-7550 6575)(-7900 6575);
WIRE 16 -1 (-7900 6625)(-7900 6575);
WIRE 16 -1 (-7250 6575)(-7550 6575);
WIRE 16 -1 (-7550 6475)(-7550 6575);
WIRE 16 -1 (-6975 6575)(-7250 6575);
WIRE 16 -1 (-7250 6475)(-7250 6575);
WIRE 16 -1 (-6975 6575)(-6975 6475);
WIRE 16 -1 (-2150 3600)(-2400 3600);
WIRE 16 -1 (-2150 3500)(-2150 3600);
WIRE 16 -1 (-2150 2925)(-2150 3000);
WIRE 16 -1 (-2150 3000)(-2400 3000);
WIRE 16 -1 (-5575 6500)(-5975 6500);
FORCEPROP 2 LAST SIG_NAME PWRGD_PVDDCR_CPU0_P0
J 2
(-5685 6510);
DISPLAY 0.489362 (-5685 6510);
WIRE 16 -1 (-5975 6500)(-5975 6625);
WIRE 16 -1 (-5975 6500)(-6150 6500);
WIRE 16 -1 (-5975 6625)(-6350 6625);
WIRE 16 -1 (-5575 6350)(-6150 6350);
FORCEPROP 2 LAST SIG_NAME PVDDCR_CPU0_P0_EN
J 2
(-5760 6360);
DISPLAY 0.489362 (-5760 6360);
WIRE 17 273 (-8750 625)(-7550 625);
WIRE 17 273 (-8750 1000)(-8750 625);
WIRE 17 273 (-7550 1000)(-7550 625);
WIRE 17 273 (-8750 1000)(-7550 1000);
WIRE 16 -1 (-5950 4625)(-5550 4625);
FORCEPROP 2 LAST SIG_NAME SMB_SCM_2_R3_SCL
J 0
(-5910 4635);
DISPLAY 0.489362 (-5910 4635);
WIRE 16 -1 (-7675 1700)(-7675 1825);
WIRE 16 -1 (-7500 1825)(-7675 1825);
FORCEPROP 2 LAST SIG_NAME PVDDCR_SOC_P0_EN_RC
J 2
(-7535 1835);
DISPLAY 0.489362 (-7535 1835);
FORCEPROP 2 LASTPROP $XRERR UNIQUE?
J 0
(-7775 1835);
DISPLAY 0.638298 (-7775 1835);
PAINT MONO (-7775 1835);
DISPLAY INVISIBLE (-7775 1835);
WIRE 16 -1 (-7950 1825)(-7675 1825);
WIRE 16 -1 (-8050 1825)(-7950 1825);
WIRE 16 -1 (-7950 1825)(-7950 1675);
WIRE 16 -1 (-6000 1400)(-6275 1400);
FORCEPROP 2 LAST SIG_NAME PWRGD_PVDDCR_SOC_P0
J 2
(-6135 1410);
DISPLAY 0.489362 (-6135 1410);
WIRE 16 -1 (-6275 1400)(-6275 1525);
WIRE 16 -1 (-6275 1400)(-6600 1400);
WIRE 16 -1 (-6275 1525)(-6650 1525);
WIRE 16 -1 (-5950 4675)(-5550 4675);
FORCEPROP 2 LAST SIG_NAME SMB_SCM_2_R3_SDA
J 0
(-5885 4685);
DISPLAY 0.489362 (-5885 4685);
WIRE 16 -1 (-5600 5050)(-5650 5050);
WIRE 16 -1 (-5650 4925)(-5650 5050);
WIRE 16 -1 (-5650 5050)(-6325 5050);
FORCEPROP 2 LAST SIG_NAME PVDDCR_CPU0_P0_PMALERT
J 0
(-6285 5060);
DISPLAY 0.489362 (-6285 5060);
WIRE 16 -1 (-5225 4925)(-5650 4925);
WIRE 16 -1 (-5225 4925)(-5225 4875);
WIRE 16 -1 (-7325 4450)(-6625 4450);
FORCEPROP 2 LAST SIG_NAME VSENSE_PVDDCR_CPU0_P0_DP
J 2
(-6760 4460);
DISPLAY 0.489362 (-6760 4460);
WIRE 16 -1 (-5700 4450)(-6625 4450);
WIRE 16 -1 (-6625 4550)(-6625 4450);
WIRE 16 -1 (-8250 1825)(-8650 1825);
FORCEPROP 2 LAST SIG_NAME PVDDCR_SOC_P0_EN
J 2
(-8310 1835);
DISPLAY 0.489362 (-8310 1835);
WIRE 16 -1 (-6225 2500)(-5650 2500);
FORCEPROP 2 LAST SIG_NAME PVDDCR_CPU0_P0_OCP_N
J 0
(-6210 2510);
DISPLAY 0.489362 (-6210 2510);
WIRE 16 -1 (-7350 2325)(-7350 2250);
WIRE 16 -1 (-6975 2250)(-7350 2250);
FORCEPROP 2 LAST SIG_NAME PVDDCR_SOC_P0_EN_GD
J 2
(-6885 2200);
DISPLAY 0.489362 (-6885 2200);
FORCEPROP 2 LASTPROP $XRERR UNIQUE?
J 0
(-7125 2200);
DISPLAY 0.638298 (-7125 2200);
PAINT MONO (-7125 2200);
DISPLAY INVISIBLE (-7125 2200);
WIRE 16 -1 (-7350 2025)(-7350 2250);
WIRE 16 -1 (-6225 2650)(-5650 2650);
FORCEPROP 2 LAST SIG_NAME PVDDCR_CPU0_P0_RESET_N
J 0
(-6210 2660);
DISPLAY 0.489362 (-6210 2660);
WIRE 16 -1 (-6275 5200)(-5600 5200);
FORCEPROP 2 LAST SIG_NAME SMB_SCM_2_R3_SDA
J 0
(-6285 5210);
DISPLAY 0.489362 (-6285 5210);
WIRE 16 -1 (-6275 5350)(-5600 5350);
FORCEPROP 2 LAST SIG_NAME SMB_SCM_2_R3_SCL
J 0
(-6285 5360);
DISPLAY 0.489362 (-6285 5360);
CIRCLE (-8150 5375)(-8025 5375);
PAINT YELLOW (-8150 5375);
DOT 1 (-6625 4450);
DOT 1 (-7850 5750);
DOT 1 (-6975 6050);
DOT 1 (-7250 5900);
DOT 1 (-5200 6350);
DOT 1 (-5650 5050);
DOT 1 (-2325 1600);
CIRCLE (-5600 3400)(-5475 3400);
PAINT YELLOW (-5600 3400);
DOT 1 (-7550 5750);
DOT 1 (-5650 2250);
DOT 1 (-5350 2650);
DOT 1 (-5250 3100);
DOT 1 (-5325 4200);
DOT 1 (-5200 6500);
DOT 1 (-6275 1400);
DOT 1 (-7675 1450);
DOT 1 (-7675 1825);
DOT 1 (-7550 6575);
DOT 1 (-5325 4450);
DOT 1 (-7900 5600);
DOT 1 (-7900 6575);
DOT 1 (-7350 2250);
DOT 1 (-6525 1225);
DOT 1 (-6050 1225);
DOT 1 (-6675 1900);
DOT 1 (-7350 2575);
DOT 1 (-6625 3100);
DOT 1 (-6625 3350);
DOT 1 (-6625 4200);
DOT 1 (-5625 1400);
DOT 1 (-5250 1050);
DOT 1 (-4875 1050);
DOT 1 (-5250 3350);
DOT 1 (-4750 2500);
DOT 1 (-7400 5900);
DOT 1 (-7175 6050);
DOT 1 (-5200 6775);
DOT 1 (-2950 1300);
DOT 1 (-2775 6200);
DOT 1 (-2500 6200);
DOT 1 (-2775 6675);
DOT 1 (-2475 6675);
DOT 1 (-5650 2125);
DOT 1 (-7250 6575);
DOT 1 (-5975 6500);
DOT 1 (-7625 5750);
CIRCLE (-5625 4400)(-5500 4400);
PAINT YELLOW (-5625 4400);
DOT 1 (-6675 1650);
DOT 1 (-5625 1650);
DOT 1 (-7950 1825);
FORCENOTE
PU42 = TBD/XDPE192C3B
(-1200 2550) 0;
DISPLAY LEFT (-1200 2550);
DISPLAY 1.021277 (-1200 2550);
PAINT WHITE (-1200 2550);
FORCENOTE
PR290 = CS25362FB02
(-1200 2475) 0;
DISPLAY LEFT (-1200 2475);
DISPLAY 1.021277 (-1200 2475);
PAINT WHITE (-1200 2475);
FORCENOTE
2ND SOURCE:INFENEON BOM
(-1200 2650) 0;
DISPLAY LEFT (-1200 2650);
DISPLAY 1.276596 (-1200 2650);
PAINT WHITE (-1200 2650);
FORCENOTE
PU42 = TBD/RAA229620GNP#HA0
(-1200 2875) 0;
DISPLAY LEFT (-1200 2875);
DISPLAY 1.021277 (-1200 2875);
PAINT WHITE (-1200 2875);
FORCENOTE
MAIN SOURCE:RENESAS BOM
(-1200 2975) 0;
DISPLAY LEFT (-1200 2975);
DISPLAY 1.276596 (-1200 2975);
PAINT WHITE (-1200 2975);
FORCENOTE
BOM NOTE
(-1200 3075) 0;
DISPLAY LEFT (-1200 3075);
DISPLAY 1.595745 (-1200 3075);
PAINT WHITE (-1200 3075);
FORCENOTE
PMBUS ADDRESS AND CONFIG
(-8775 1050) 0;
DISPLAY LEFT (-8775 1050);
DISPLAY 1.170213 (-8775 1050);
PAINT WHITE (-8775 1050);
FORCENOTE
CONFIG/R
(-7875 925) 0;
DISPLAY LEFT (-7875 925);
DISPLAY 0.808511 (-7875 925);
PAINT WHITE (-7875 925);
FORCENOTE
ADDRESS(7-BIT)
(-8450 925) 0;
DISPLAY LEFT (-8450 925);
DISPLAY 0.808511 (-8450 925);
PAINT WHITE (-8450 925);
FORCENOTE
/681 OHM
(-7875 750) 0;
DISPLAY LEFT (-7875 750);
DISPLAY 0.638298 (-7875 750);
PAINT WHITE (-7875 750);
FORCENOTE
0X4F
(-8225 675) 0;
DISPLAY LEFT (-8225 675);
DISPLAY 0.638298 (-8225 675);
PAINT WHITE (-8225 675);
FORCENOTE
PR5 = CS21002FB06
(-1200 2400) 0;
DISPLAY LEFT (-1200 2400);
DISPLAY 1.021277 (-1200 2400);
PAINT WHITE (-1200 2400);
FORCENOTE
PR306,PR307 = CS01002FB07
(-1200 2250) 0;
DISPLAY LEFT (-1200 2250);
DISPLAY 1.021277 (-1200 2250);
PAINT WHITE (-1200 2250);
FORCENOTE
PC472,PC469 = CH11006JB00
(-1200 2100) 0;
DISPLAY LEFT (-1200 2100);
DISPLAY 1.021277 (-1200 2100);
PAINT WHITE (-1200 2100);
FORCENOTE
PC462 = CH3104J1B00
(-1200 1950) 0;
DISPLAY LEFT (-1200 1950);
DISPLAY 1.021277 (-1200 1950);
PAINT WHITE (-1200 1950);
FORCENOTE
3RD SOURCE:MPS BOM
(-1200 1675) 0;
DISPLAY LEFT (-1200 1675);
DISPLAY 1.276596 (-1200 1675);
PAINT WHITE (-1200 1675);
FORCENOTE
PR290,PC462,PR531 = EMPTY
(-1175 1425) 0;
DISPLAY LEFT (-1175 1425);
DISPLAY 1.021277 (-1175 1425);
PAINT WHITE (-1175 1425);
FORCENOTE
PR292,PR314 = CS37502FB05
(-1175 1275) 0;
DISPLAY LEFT (-1175 1275);
DISPLAY 1.021277 (-1175 1275);
PAINT WHITE (-1175 1275);
FORCENOTE
PC469,PC472 = CH31004KB17
(-1175 1125) 0;
DISPLAY LEFT (-1175 1125);
DISPLAY 1.021277 (-1175 1125);
PAINT WHITE (-1175 1125);
FORCENOTE
PC470 =CH5103KEB01
(-1175 975) 0;
DISPLAY LEFT (-1175 975);
DISPLAY 1.021277 (-1175 975);
PAINT WHITE (-1175 975);
FORCENOTE
PC7 = CH21006JB10
(-1175 1050) 0;
DISPLAY LEFT (-1175 1050);
DISPLAY 1.021277 (-1175 1050);
PAINT WHITE (-1175 1050);
FORCENOTE
PR599 = CS24992FB07
(-1175 1200) 0;
DISPLAY LEFT (-1175 1200);
DISPLAY 1.021277 (-1175 1200);
PAINT WHITE (-1175 1200);
FORCENOTE
PR440,PR441,PC463,PC464 = EMPTY
(-1175 1350) 0;
DISPLAY LEFT (-1175 1350);
DISPLAY 1.021277 (-1175 1350);
PAINT WHITE (-1175 1350);
FORCENOTE
PR5 = CS00002JB13
(-1175 1500) 0;
DISPLAY LEFT (-1175 1500);
DISPLAY 1.021277 (-1175 1500);
PAINT WHITE (-1175 1500);
FORCENOTE
PU42 = TBD/MP2857GQKT-001C-Z
(-1175 1575) 0;
DISPLAY LEFT (-1175 1575);
DISPLAY 1.021277 (-1175 1575);
PAINT WHITE (-1175 1575);
FORCENOTE
PC463,PC464 = CH12206KB14
(-1200 2025) 0;
DISPLAY LEFT (-1200 2025);
DISPLAY 1.021277 (-1200 2025);
PAINT WHITE (-1200 2025);
FORCENOTE
PC470 = CH5103KEB01
(-1200 2175) 0;
DISPLAY LEFT (-1200 2175);
DISPLAY 1.021277 (-1200 2175);
PAINT WHITE (-1200 2175);
FORCENOTE
PR531,PR440,PR441 = EMPTY
(-1200 2325) 0;
DISPLAY LEFT (-1200 2325);
DISPLAY 1.021277 (-1200 2325);
PAINT WHITE (-1200 2325);
FORCENOTE
0X4F
(-8225 750) 0;
DISPLAY LEFT (-8225 750);
DISPLAY 0.638298 (-8225 750);
PAINT WHITE (-8225 750);
FORCENOTE
MPS
(-8675 675) 0;
DISPLAY LEFT (-8675 675);
DISPLAY 0.638298 (-8675 675);
PAINT WHITE (-8675 675);
FORCENOTE
INFINEON
(-8675 750) 0;
DISPLAY LEFT (-8675 750);
DISPLAY 0.638298 (-8675 750);
PAINT WHITE (-8675 750);
FORCENOTE
VR
(-8675 925) 0;
DISPLAY LEFT (-8675 925);
DISPLAY 0.808511 (-8675 925);
PAINT WHITE (-8675 925);
FORCENOTE
/75K OHM
(-7875 675) 0;
DISPLAY LEFT (-7875 675);
DISPLAY 0.638298 (-7875 675);
PAINT WHITE (-7875 675);
FORCENOTE
EDC=230A
(-1225 6300) 0;
DISPLAY LEFT (-1225 6300);
DISPLAY 0.936170 (-1225 6300);
PAINT WHITE (-1225 6300);
FORCENOTE
TDC=175A
(-1225 6375) 0;
DISPLAY LEFT (-1225 6375);
DISPLAY 0.936170 (-1225 6375);
PAINT WHITE (-1225 6375);
FORCENOTE
MAX AC=VID+200MV
(-1225 6525) 0;
DISPLAY LEFT (-1225 6525);
DISPLAY 0.936170 (-1225 6525);
PAINT WHITE (-1225 6525);
FORCENOTE
DC=+/-20MV
(-1225 6600) 0;
DISPLAY LEFT (-1225 6600);
DISPLAY 0.936170 (-1225 6600);
PAINT WHITE (-1225 6600);
FORCENOTE
VID=0.55-1.5V
(-1225 6675) 0;
DISPLAY LEFT (-1225 6675);
DISPLAY 0.936170 (-1225 6675);
PAINT WHITE (-1225 6675);
FORCENOTE
PVDDCR_CPU0_P0 SPECFICATION
(-1225 6897) 0;
DISPLAY LEFT (-1225 6897);
DISPLAY 1.170213 (-1225 6897);
PAINT WHITE (-1225 6897);
FORCENOTE
DEFAULT POWER-ON VID=0.9V
(-1225 6750) 0;
DISPLAY LEFT (-1225 6750);
DISPLAY 0.936170 (-1225 6750);
PAINT WHITE (-1225 6750);
FORCENOTE
TRACE SPACING = 5MIL
(-7500 2825) 0;
DISPLAY LEFT (-7500 2825);
DISPLAY 0.808511 (-7500 2825);
PAINT WHITE (-7500 2825);
FORCENOTE
TRACE WIDTH = 10MIL
(-7525 4000) 0;
DISPLAY LEFT (-7525 4000);
DISPLAY 0.808511 (-7525 4000);
PAINT WHITE (-7525 4000);
FORCENOTE
DIFFERENTIAL PAIR
(-7525 4075) 0;
DISPLAY LEFT (-7525 4075);
DISPLAY 0.808511 (-7525 4075);
PAINT WHITE (-7525 4075);
FORCENOTE
TRACE SPACING = 5MIL
(-7525 3925) 0;
DISPLAY LEFT (-7525 3925);
DISPLAY 0.808511 (-7525 3925);
PAINT WHITE (-7525 3925);
FORCENOTE
0/681 OHM
(-7875 825) 0;
DISPLAY LEFT (-7875 825);
DISPLAY 0.638298 (-7875 825);
PAINT WHITE (-7875 825);
FORCENOTE
RENESAS
(-8675 825) 0;
DISPLAY LEFT (-8675 825);
DISPLAY 0.638298 (-8675 825);
PAINT WHITE (-8675 825);
FORCENOTE
EDC=130A
(-1225 4950) 0;
DISPLAY LEFT (-1225 4950);
DISPLAY 0.936170 (-1225 4950);
PAINT WHITE (-1225 4950);
FORCENOTE
TDC=105A
(-1225 5025) 0;
DISPLAY LEFT (-1225 5025);
DISPLAY 0.936170 (-1225 5025);
PAINT WHITE (-1225 5025);
FORCENOTE
MAX AC=VID+150MV
(-1225 5175) 0;
DISPLAY LEFT (-1225 5175);
DISPLAY 0.936170 (-1225 5175);
PAINT WHITE (-1225 5175);
FORCENOTE
MIN AC=VID-150MV
(-1225 5100) 0;
DISPLAY LEFT (-1225 5100);
DISPLAY 0.936170 (-1225 5100);
PAINT WHITE (-1225 5100);
FORCENOTE
OCP=156A (EDC*1.2)
(-1225 4875) 0;
DISPLAY LEFT (-1225 4875);
DISPLAY 0.936170 (-1225 4875);
PAINT WHITE (-1225 4875);
FORCENOTE
MAX LOAD STEP=45A
(-1225 4800) 0;
DISPLAY LEFT (-1225 4800);
DISPLAY 0.936170 (-1225 4800);
PAINT WHITE (-1225 4800);
FORCENOTE
0X61
(-8225 825) 0;
DISPLAY LEFT (-8225 825);
DISPLAY 0.638298 (-8225 825);
PAINT WHITE (-8225 825);
FORCENOTE
TRACE WIDTH = 10MIL
(-7500 2900) 0;
DISPLAY LEFT (-7500 2900);
DISPLAY 0.808511 (-7500 2900);
PAINT WHITE (-7500 2900);
FORCENOTE
DIFFERENTIAL PAIR
(-7500 2975) 0;
DISPLAY LEFT (-7500 2975);
DISPLAY 0.808511 (-7500 2975);
PAINT WHITE (-7500 2975);
FORCENOTE
DC=+/-20MV
(-1225 5250) 0;
DISPLAY LEFT (-1225 5250);
DISPLAY 0.936170 (-1225 5250);
PAINT WHITE (-1225 5250);
FORCENOTE
VID=0.75-1.2V
(-1225 5325) 0;
DISPLAY LEFT (-1225 5325);
DISPLAY 0.936170 (-1225 5325);
PAINT WHITE (-1225 5325);
FORCENOTE
MIN AC=VID-EDC*LL-110MV
(-1225 6450) 0;
DISPLAY LEFT (-1225 6450);
DISPLAY 0.936170 (-1225 6450);
PAINT WHITE (-1225 6450);
FORCENOTE
OCP=276A (EDC*1.2)
(-1225 6225) 0;
DISPLAY LEFT (-1225 6225);
DISPLAY 0.936170 (-1225 6225);
PAINT WHITE (-1225 6225);
FORCENOTE
MAX LOAD STEP=200A
(-1225 6150) 0;
DISPLAY LEFT (-1225 6150);
DISPLAY 0.936170 (-1225 6150);
PAINT WHITE (-1225 6150);
FORCENOTE
MAX LOAD RELEASE=200A
(-1225 6075) 0;
DISPLAY LEFT (-1225 6075);
DISPLAY 0.936170 (-1225 6075);
PAINT WHITE (-1225 6075);
FORCENOTE
LOAD-LINE=0.4MOHM
(-1225 6000) 0;
DISPLAY LEFT (-1225 6000);
DISPLAY 0.936170 (-1225 6000);
PAINT WHITE (-1225 6000);
FORCENOTE
WORK FREQUENCY=600KHZ
(-1225 5925) 0;
DISPLAY LEFT (-1225 5925);
DISPLAY 0.936170 (-1225 5925);
PAINT WHITE (-1225 5925);
FORCENOTE
EFFICIENCY > 90% @TDC
(-1225 5850) 0;
DISPLAY LEFT (-1225 5850);
DISPLAY 0.936170 (-1225 5850);
PAINT WHITE (-1225 5850);
FORCENOTE
SVI3 ADDRESS=PORT0 (0X1)
(-1225 5775) 0;
DISPLAY LEFT (-1225 5775);
DISPLAY 0.936170 (-1225 5775);
PAINT WHITE (-1225 5775);
FORCENOTE
DEFAULT POWER-ON VID=0.9V
(-1225 5400) 0;
DISPLAY LEFT (-1225 5400);
DISPLAY 0.936170 (-1225 5400);
PAINT WHITE (-1225 5400);
FORCENOTE
PVDDCR_SOC_P0 SPECFICATION
(-1225 5525) 0;
DISPLAY LEFT (-1225 5525);
DISPLAY 1.276596 (-1225 5525);
PAINT WHITE (-1225 5525);
FORCENOTE
MAX LOAD RELEASE=95A
(-1225 4725) 0;
DISPLAY LEFT (-1225 4725);
DISPLAY 0.936170 (-1225 4725);
PAINT WHITE (-1225 4725);
FORCENOTE
WORK FREQUENCY=600KHZ
(-1225 4650) 0;
DISPLAY LEFT (-1225 4650);
DISPLAY 0.936170 (-1225 4650);
PAINT WHITE (-1225 4650);
FORCENOTE
EFFICIENCY > 90% @TDC
(-1225 4575) 0;
DISPLAY LEFT (-1225 4575);
DISPLAY 0.936170 (-1225 4575);
PAINT WHITE (-1225 4575);
FORCENOTE
SVI3 ADDRESS=PORT0 (0X2)
(-1225 4500) 0;
DISPLAY LEFT (-1225 4500);
DISPLAY 0.936170 (-1225 4500);
PAINT WHITE (-1225 4500);
FORCENOTE
IRM REV1.09
(-1225 5700) 0;
DISPLAY LEFT (-1225 5700);
DISPLAY 0.936170 (-1225 5700);
PAINT WHITE (-1225 5700);
FORCENOTE
IRM REV1.09
(-1225 4425) 0;
DISPLAY LEFT (-1225 4425);
DISPLAY 0.936170 (-1225 4425);
PAINT WHITE (-1225 4425);
QUIT
